FILE_TYPE = MACRO_DRAWING;
SET COLOR_WIRE YELLOW;
SET COLOR_PROP ORANGE;
SET COLOR_DOT WHITE;
SET COLOR_ARC YELLOW;
SET COLOR_BODY GREEN;
SET COLOR_NOTE PURPLE;
SET PROP_DISPLAY VALUE;
SET PAGE_NUMBER P12;
SET PATH_NUMBER P513;
FORCEADD UNIVERSAL_POWER..1
(-1875 -175);
FORCEPROP 3 LASTPIN (-1875 -225) SIG_NAME PGPPA_BMC_AUX\g
J 0
(-1865 -215);
DISPLAY 0.659574 (-1865 -215);
PAINT MONO (-1865 -215);
DISPLAY INVISIBLE (-1865 -215);
FORCEPROP 1 LAST HDL_POWER PGPPA_BMC_AUX
J 1
(-1875 -125);
DISPLAY 0.702128 (-1875 -125);
PAINT GREEN (-1875 -125);
FORCEPROP 1 LAST PATH I1
J 0
(-1825 -150);
DISPLAY 0.872340 (-1825 -150);
PAINT AQUA (-1825 -150);
DISPLAY INVISIBLE (-1825 -150);
FORCEPROP 2 LAST CDS_LIB logical_power
J 0
(-1875 -175);
DISPLAY INVISIBLE (-1875 -175);
FORCEADD OFFPAGE..2
R 2
(-2125 450);
FORCEPROP 2 LAST $XR1 10 
J 0
(-2469 450);
DISPLAY 0.638298 (-2469 450);
PAINT MONO (-2469 450);
FORCEPROP 2 LAST $XR0 11 
J 0
(-2379 450);
DISPLAY 0.638298 (-2379 450);
PAINT MONO (-2379 450);
FORCEPROP 2 LAST PATH I10
J 0
(-2300 500);
DISPLAY 1.021277 (-2300 500);
DISPLAY INVISIBLE (-2300 500);
FORCEPROP 1 LAST COMMENT_BODY TRUE
J 2
(-2080 355);
DISPLAY 0.872340 (-2080 355);
PAINT PEACH (-2080 355);
DISPLAY INVISIBLE (-2080 355);
FORCEPROP 1 LAST OFFPAGE TRUE
J 2
(-2450 325);
DISPLAY 0.872340 (-2450 325);
PAINT GREEN (-2450 325);
DISPLAY INVISIBLE (-2450 325);
FORCEPROP 2 LAST CDS_LIB standard
J 0
(-2125 450);
DISPLAY INVISIBLE (-2125 450);
FORCEADD OFFPAGE..3
(3775 2200);
FORCEPROP 2 LAST $XR0 20 
J 0
(3989 2200);
DISPLAY 0.638298 (3989 2200);
PAINT MONO (3989 2200);
FORCEPROP 2 LAST PATH I103
J 0
(4000 2250);
DISPLAY 1.021277 (4000 2250);
DISPLAY INVISIBLE (4000 2250);
FORCEPROP 1 LAST COMMENT_BODY TRUE
J 0
(3725 2100);
DISPLAY 0.872340 (3725 2100);
PAINT PEACH (3725 2100);
DISPLAY INVISIBLE (3725 2100);
FORCEPROP 1 LAST OFFPAGE TRUE
J 0
(4100 2075);
DISPLAY 0.872340 (4100 2075);
PAINT GREEN (4100 2075);
DISPLAY INVISIBLE (4100 2075);
FORCEPROP 2 LAST CDS_LIB standard
J 0
(3775 2200);
DISPLAY INVISIBLE (3775 2200);
FORCEADD OFFPAGE..2
(3775 2350);
FORCEPROP 2 LAST $XR0 20 
J 0
(3964 2350);
DISPLAY 0.638298 (3964 2350);
PAINT MONO (3964 2350);
FORCEPROP 2 LAST PATH I104
J 0
(3975 2400);
DISPLAY 1.021277 (3975 2400);
DISPLAY INVISIBLE (3975 2400);
FORCEPROP 1 LAST COMMENT_BODY TRUE
J 0
(3730 2255);
DISPLAY 0.872340 (3730 2255);
PAINT PEACH (3730 2255);
DISPLAY INVISIBLE (3730 2255);
FORCEPROP 1 LAST OFFPAGE TRUE
J 0
(4100 2225);
DISPLAY 0.872340 (4100 2225);
PAINT GREEN (4100 2225);
DISPLAY INVISIBLE (4100 2225);
FORCEPROP 2 LAST CDS_LIB standard
J 0
(3775 2350);
DISPLAY INVISIBLE (3775 2350);
FORCEADD OFFPAGE..2
(3775 2300);
FORCEPROP 2 LAST $XR0 20 
J 0
(3964 2300);
DISPLAY 0.638298 (3964 2300);
PAINT MONO (3964 2300);
FORCEPROP 2 LAST PATH I105
J 0
(3975 2350);
DISPLAY 1.021277 (3975 2350);
DISPLAY INVISIBLE (3975 2350);
FORCEPROP 1 LAST COMMENT_BODY TRUE
J 0
(3730 2205);
DISPLAY 0.872340 (3730 2205);
PAINT PEACH (3730 2205);
DISPLAY INVISIBLE (3730 2205);
FORCEPROP 1 LAST OFFPAGE TRUE
J 0
(4100 2175);
DISPLAY 0.872340 (4100 2175);
PAINT GREEN (4100 2175);
DISPLAY INVISIBLE (4100 2175);
FORCEPROP 2 LAST CDS_LIB standard
J 0
(3775 2300);
DISPLAY INVISIBLE (3775 2300);
FORCEADD OFFPAGE..3
(3775 2250);
FORCEPROP 2 LAST $XR0 20 
J 0
(3989 2250);
DISPLAY 0.638298 (3989 2250);
PAINT MONO (3989 2250);
FORCEPROP 2 LAST PATH I106
J 0
(4000 2300);
DISPLAY 1.021277 (4000 2300);
DISPLAY INVISIBLE (4000 2300);
FORCEPROP 1 LAST COMMENT_BODY TRUE
J 0
(3725 2150);
DISPLAY 0.872340 (3725 2150);
PAINT PEACH (3725 2150);
DISPLAY INVISIBLE (3725 2150);
FORCEPROP 1 LAST OFFPAGE TRUE
J 0
(4100 2125);
DISPLAY 0.872340 (4100 2125);
PAINT GREEN (4100 2125);
DISPLAY INVISIBLE (4100 2125);
FORCEPROP 2 LAST CDS_LIB standard
J 0
(3775 2250);
DISPLAY INVISIBLE (3775 2250);
FORCEADD TAP..1
(4175 2400);
FORCEPROP 3 LASTPIN (4125 2400) SIG_NAME M_BMC_DDR4_MA<13>
J 0
(4135 2410);
DISPLAY 0.659574 (4135 2410);
PAINT MONO (4135 2410);
DISPLAY INVISIBLE (4135 2410);
FORCEPROP 1 LASTPIN (4125 2400) BN 13
J 0
(4113 2408);
DISPLAY 0.702128 (4113 2408);
PAINT VIOLET (4113 2408);
FORCEPROP 1 LAST PATH I107
J 0
(4173 2400);
DISPLAY 0.872340 (4173 2400);
PAINT GREEN (4173 2400);
DISPLAY INVISIBLE (4173 2400);
FORCEPROP 1 LAST HDL_TAP TRUE
J 0
(4500 2275);
DISPLAY 0.872340 (4500 2275);
DISPLAY INVISIBLE (4500 2275);
FORCEPROP 1 LAST BODY_TYPE PLUMBING
J 0
(4175 2450);
DISPLAY 0.872340 (4175 2450);
PAINT GREEN (4175 2450);
DISPLAY INVISIBLE (4175 2450);
FORCEPROP 2 LAST CDS_LIB standard
J 0
(4175 2400);
DISPLAY INVISIBLE (4175 2400);
FORCEADD TAP..1
(4175 2450);
FORCEPROP 3 LASTPIN (4125 2450) SIG_NAME M_BMC_DDR4_MA<12>
J 0
(4135 2460);
DISPLAY 0.659574 (4135 2460);
PAINT MONO (4135 2460);
DISPLAY INVISIBLE (4135 2460);
FORCEPROP 1 LASTPIN (4125 2450) BN 12
J 0
(4113 2458);
DISPLAY 0.702128 (4113 2458);
PAINT VIOLET (4113 2458);
FORCEPROP 1 LAST PATH I108
J 0
(4173 2450);
DISPLAY 0.872340 (4173 2450);
PAINT GREEN (4173 2450);
DISPLAY INVISIBLE (4173 2450);
FORCEPROP 1 LAST HDL_TAP TRUE
J 0
(4500 2325);
DISPLAY 0.872340 (4500 2325);
DISPLAY INVISIBLE (4500 2325);
FORCEPROP 1 LAST BODY_TYPE PLUMBING
J 0
(4175 2500);
DISPLAY 0.872340 (4175 2500);
PAINT GREEN (4175 2500);
DISPLAY INVISIBLE (4175 2500);
FORCEPROP 2 LAST CDS_LIB standard
J 0
(4175 2450);
DISPLAY INVISIBLE (4175 2450);
FORCEADD TAP..1
(4175 2500);
FORCEPROP 3 LASTPIN (4125 2500) SIG_NAME M_BMC_DDR4_MA<11>
J 0
(4135 2510);
DISPLAY 0.659574 (4135 2510);
PAINT MONO (4135 2510);
DISPLAY INVISIBLE (4135 2510);
FORCEPROP 1 LASTPIN (4125 2500) BN 11
J 0
(4113 2508);
DISPLAY 0.702128 (4113 2508);
PAINT VIOLET (4113 2508);
FORCEPROP 1 LAST PATH I109
J 0
(4173 2500);
DISPLAY 0.872340 (4173 2500);
PAINT GREEN (4173 2500);
DISPLAY INVISIBLE (4173 2500);
FORCEPROP 1 LAST HDL_TAP TRUE
J 0
(4500 2375);
DISPLAY 0.872340 (4500 2375);
DISPLAY INVISIBLE (4500 2375);
FORCEPROP 1 LAST BODY_TYPE PLUMBING
J 0
(4175 2550);
DISPLAY 0.872340 (4175 2550);
PAINT GREEN (4175 2550);
DISPLAY INVISIBLE (4175 2550);
FORCEPROP 2 LAST CDS_LIB standard
J 0
(4175 2500);
DISPLAY INVISIBLE (4175 2500);
FORCEADD OFFPAGE..2
R 2
(-2125 500);
FORCEPROP 2 LAST $XR1 10 
J 0
(-2469 500);
DISPLAY 0.638298 (-2469 500);
PAINT MONO (-2469 500);
FORCEPROP 2 LAST $XR0 11 
J 0
(-2379 500);
DISPLAY 0.638298 (-2379 500);
PAINT MONO (-2379 500);
FORCEPROP 2 LAST PATH I11
J 0
(-2300 550);
DISPLAY 1.021277 (-2300 550);
DISPLAY INVISIBLE (-2300 550);
FORCEPROP 1 LAST COMMENT_BODY TRUE
J 2
(-2080 405);
DISPLAY 0.872340 (-2080 405);
PAINT PEACH (-2080 405);
DISPLAY INVISIBLE (-2080 405);
FORCEPROP 1 LAST OFFPAGE TRUE
J 2
(-2450 375);
DISPLAY 0.872340 (-2450 375);
PAINT GREEN (-2450 375);
DISPLAY INVISIBLE (-2450 375);
FORCEPROP 2 LAST CDS_LIB standard
J 0
(-2125 500);
DISPLAY INVISIBLE (-2125 500);
FORCEADD TAP..1
(4175 2550);
FORCEPROP 3 LASTPIN (4125 2550) SIG_NAME M_BMC_DDR4_MA<10>
J 0
(4135 2560);
DISPLAY 0.659574 (4135 2560);
PAINT MONO (4135 2560);
DISPLAY INVISIBLE (4135 2560);
FORCEPROP 1 LASTPIN (4125 2550) BN 10
J 0
(4113 2558);
DISPLAY 0.702128 (4113 2558);
PAINT VIOLET (4113 2558);
FORCEPROP 1 LAST PATH I110
J 0
(4173 2550);
DISPLAY 0.872340 (4173 2550);
PAINT GREEN (4173 2550);
DISPLAY INVISIBLE (4173 2550);
FORCEPROP 1 LAST HDL_TAP TRUE
J 0
(4500 2425);
DISPLAY 0.872340 (4500 2425);
DISPLAY INVISIBLE (4500 2425);
FORCEPROP 1 LAST BODY_TYPE PLUMBING
J 0
(4175 2600);
DISPLAY 0.872340 (4175 2600);
PAINT GREEN (4175 2600);
DISPLAY INVISIBLE (4175 2600);
FORCEPROP 2 LAST CDS_LIB standard
J 0
(4175 2550);
DISPLAY INVISIBLE (4175 2550);
FORCEADD TAP..1
(4175 2650);
FORCEPROP 3 LASTPIN (4125 2650) SIG_NAME M_BMC_DDR4_MA<8>
J 0
(4135 2660);
DISPLAY 0.659574 (4135 2660);
PAINT MONO (4135 2660);
DISPLAY INVISIBLE (4135 2660);
FORCEPROP 1 LASTPIN (4125 2650) BN 8
J 0
(4113 2658);
DISPLAY 0.702128 (4113 2658);
PAINT VIOLET (4113 2658);
FORCEPROP 1 LAST PATH I111
J 0
(4173 2650);
DISPLAY 0.872340 (4173 2650);
PAINT GREEN (4173 2650);
DISPLAY INVISIBLE (4173 2650);
FORCEPROP 1 LAST HDL_TAP TRUE
J 0
(4500 2525);
DISPLAY 0.872340 (4500 2525);
DISPLAY INVISIBLE (4500 2525);
FORCEPROP 1 LAST BODY_TYPE PLUMBING
J 0
(4175 2700);
DISPLAY 0.872340 (4175 2700);
PAINT GREEN (4175 2700);
DISPLAY INVISIBLE (4175 2700);
FORCEPROP 2 LAST CDS_LIB standard
J 0
(4175 2650);
DISPLAY INVISIBLE (4175 2650);
FORCEADD TAP..1
(4175 2600);
FORCEPROP 3 LASTPIN (4125 2600) SIG_NAME M_BMC_DDR4_MA<9>
J 0
(4135 2610);
DISPLAY 0.659574 (4135 2610);
PAINT MONO (4135 2610);
DISPLAY INVISIBLE (4135 2610);
FORCEPROP 1 LASTPIN (4125 2600) BN 9
J 0
(4113 2608);
DISPLAY 0.702128 (4113 2608);
PAINT VIOLET (4113 2608);
FORCEPROP 1 LAST PATH I112
J 0
(4173 2600);
DISPLAY 0.872340 (4173 2600);
PAINT GREEN (4173 2600);
DISPLAY INVISIBLE (4173 2600);
FORCEPROP 1 LAST HDL_TAP TRUE
J 0
(4500 2475);
DISPLAY 0.872340 (4500 2475);
DISPLAY INVISIBLE (4500 2475);
FORCEPROP 1 LAST BODY_TYPE PLUMBING
J 0
(4175 2650);
DISPLAY 0.872340 (4175 2650);
PAINT GREEN (4175 2650);
DISPLAY INVISIBLE (4175 2650);
FORCEPROP 2 LAST CDS_LIB standard
J 0
(4175 2600);
DISPLAY INVISIBLE (4175 2600);
FORCEADD TAP..1
(4175 2700);
FORCEPROP 3 LASTPIN (4125 2700) SIG_NAME M_BMC_DDR4_MA<7>
J 0
(4135 2710);
DISPLAY 0.659574 (4135 2710);
PAINT MONO (4135 2710);
DISPLAY INVISIBLE (4135 2710);
FORCEPROP 1 LASTPIN (4125 2700) BN 7
J 0
(4113 2708);
DISPLAY 0.702128 (4113 2708);
PAINT VIOLET (4113 2708);
FORCEPROP 1 LAST PATH I113
J 0
(4173 2700);
DISPLAY 0.872340 (4173 2700);
PAINT GREEN (4173 2700);
DISPLAY INVISIBLE (4173 2700);
FORCEPROP 1 LAST HDL_TAP TRUE
J 0
(4500 2575);
DISPLAY 0.872340 (4500 2575);
DISPLAY INVISIBLE (4500 2575);
FORCEPROP 1 LAST BODY_TYPE PLUMBING
J 0
(4175 2750);
DISPLAY 0.872340 (4175 2750);
PAINT GREEN (4175 2750);
DISPLAY INVISIBLE (4175 2750);
FORCEPROP 2 LAST CDS_LIB standard
J 0
(4175 2700);
DISPLAY INVISIBLE (4175 2700);
FORCEADD TAP..1
(4175 2750);
FORCEPROP 3 LASTPIN (4125 2750) SIG_NAME M_BMC_DDR4_MA<6>
J 0
(4135 2760);
DISPLAY 0.659574 (4135 2760);
PAINT MONO (4135 2760);
DISPLAY INVISIBLE (4135 2760);
FORCEPROP 1 LASTPIN (4125 2750) BN 6
J 0
(4113 2758);
DISPLAY 0.702128 (4113 2758);
PAINT VIOLET (4113 2758);
FORCEPROP 1 LAST PATH I114
J 0
(4173 2750);
DISPLAY 0.872340 (4173 2750);
PAINT GREEN (4173 2750);
DISPLAY INVISIBLE (4173 2750);
FORCEPROP 1 LAST HDL_TAP TRUE
J 0
(4500 2625);
DISPLAY 0.872340 (4500 2625);
DISPLAY INVISIBLE (4500 2625);
FORCEPROP 1 LAST BODY_TYPE PLUMBING
J 0
(4175 2800);
DISPLAY 0.872340 (4175 2800);
PAINT GREEN (4175 2800);
DISPLAY INVISIBLE (4175 2800);
FORCEPROP 2 LAST CDS_LIB standard
J 0
(4175 2750);
DISPLAY INVISIBLE (4175 2750);
FORCEADD TAP..1
(4175 2800);
FORCEPROP 3 LASTPIN (4125 2800) SIG_NAME M_BMC_DDR4_MA<5>
J 0
(4135 2810);
DISPLAY 0.659574 (4135 2810);
PAINT MONO (4135 2810);
DISPLAY INVISIBLE (4135 2810);
FORCEPROP 1 LASTPIN (4125 2800) BN 5
J 0
(4113 2808);
DISPLAY 0.702128 (4113 2808);
PAINT VIOLET (4113 2808);
FORCEPROP 1 LAST PATH I115
J 0
(4173 2800);
DISPLAY 0.872340 (4173 2800);
PAINT GREEN (4173 2800);
DISPLAY INVISIBLE (4173 2800);
FORCEPROP 1 LAST HDL_TAP TRUE
J 0
(4500 2675);
DISPLAY 0.872340 (4500 2675);
DISPLAY INVISIBLE (4500 2675);
FORCEPROP 1 LAST BODY_TYPE PLUMBING
J 0
(4175 2850);
DISPLAY 0.872340 (4175 2850);
PAINT GREEN (4175 2850);
DISPLAY INVISIBLE (4175 2850);
FORCEPROP 2 LAST CDS_LIB standard
J 0
(4175 2800);
DISPLAY INVISIBLE (4175 2800);
FORCEADD TAP..1
(4175 2900);
FORCEPROP 3 LASTPIN (4125 2900) SIG_NAME M_BMC_DDR4_MA<3>
J 0
(4135 2910);
DISPLAY 0.659574 (4135 2910);
PAINT MONO (4135 2910);
DISPLAY INVISIBLE (4135 2910);
FORCEPROP 1 LASTPIN (4125 2900) BN 3
J 0
(4113 2908);
DISPLAY 0.702128 (4113 2908);
PAINT VIOLET (4113 2908);
FORCEPROP 1 LAST PATH I116
J 0
(4173 2900);
DISPLAY 0.872340 (4173 2900);
PAINT GREEN (4173 2900);
DISPLAY INVISIBLE (4173 2900);
FORCEPROP 1 LAST HDL_TAP TRUE
J 0
(4500 2775);
DISPLAY 0.872340 (4500 2775);
DISPLAY INVISIBLE (4500 2775);
FORCEPROP 1 LAST BODY_TYPE PLUMBING
J 0
(4175 2950);
DISPLAY 0.872340 (4175 2950);
PAINT GREEN (4175 2950);
DISPLAY INVISIBLE (4175 2950);
FORCEPROP 2 LAST CDS_LIB standard
J 0
(4175 2900);
DISPLAY INVISIBLE (4175 2900);
FORCEADD TAP..1
(4175 2850);
FORCEPROP 3 LASTPIN (4125 2850) SIG_NAME M_BMC_DDR4_MA<4>
J 0
(4135 2860);
DISPLAY 0.659574 (4135 2860);
PAINT MONO (4135 2860);
DISPLAY INVISIBLE (4135 2860);
FORCEPROP 1 LASTPIN (4125 2850) BN 4
J 0
(4113 2858);
DISPLAY 0.702128 (4113 2858);
PAINT VIOLET (4113 2858);
FORCEPROP 1 LAST PATH I117
J 0
(4173 2850);
DISPLAY 0.872340 (4173 2850);
PAINT GREEN (4173 2850);
DISPLAY INVISIBLE (4173 2850);
FORCEPROP 1 LAST HDL_TAP TRUE
J 0
(4500 2725);
DISPLAY 0.872340 (4500 2725);
DISPLAY INVISIBLE (4500 2725);
FORCEPROP 1 LAST BODY_TYPE PLUMBING
J 0
(4175 2900);
DISPLAY 0.872340 (4175 2900);
PAINT GREEN (4175 2900);
DISPLAY INVISIBLE (4175 2900);
FORCEPROP 2 LAST CDS_LIB standard
J 0
(4175 2850);
DISPLAY INVISIBLE (4175 2850);
FORCEADD TAP..1
(4175 2950);
FORCEPROP 3 LASTPIN (4125 2950) SIG_NAME M_BMC_DDR4_MA<2>
J 0
(4135 2960);
DISPLAY 0.659574 (4135 2960);
PAINT MONO (4135 2960);
DISPLAY INVISIBLE (4135 2960);
FORCEPROP 1 LASTPIN (4125 2950) BN 2
J 0
(4113 2958);
DISPLAY 0.702128 (4113 2958);
PAINT VIOLET (4113 2958);
FORCEPROP 1 LAST PATH I118
J 0
(4173 2950);
DISPLAY 0.872340 (4173 2950);
PAINT GREEN (4173 2950);
DISPLAY INVISIBLE (4173 2950);
FORCEPROP 1 LAST HDL_TAP TRUE
J 0
(4500 2825);
DISPLAY 0.872340 (4500 2825);
DISPLAY INVISIBLE (4500 2825);
FORCEPROP 1 LAST BODY_TYPE PLUMBING
J 0
(4175 3000);
DISPLAY 0.872340 (4175 3000);
PAINT GREEN (4175 3000);
DISPLAY INVISIBLE (4175 3000);
FORCEPROP 2 LAST CDS_LIB standard
J 0
(4175 2950);
DISPLAY INVISIBLE (4175 2950);
FORCEADD OFFPAGE..3
(4850 1950);
FORCEPROP 2 LAST $XR0 10 
J 0
(5064 1950);
DISPLAY 0.638298 (5064 1950);
PAINT MONO (5064 1950);
FORCEPROP 2 LAST PATH I119
J 0
(5075 2000);
DISPLAY 1.021277 (5075 2000);
DISPLAY INVISIBLE (5075 2000);
FORCEPROP 1 LAST COMMENT_BODY TRUE
J 0
(4800 1850);
DISPLAY 0.872340 (4800 1850);
PAINT PEACH (4800 1850);
DISPLAY INVISIBLE (4800 1850);
FORCEPROP 1 LAST OFFPAGE TRUE
J 0
(5175 1825);
DISPLAY 0.872340 (5175 1825);
PAINT GREEN (5175 1825);
DISPLAY INVISIBLE (5175 1825);
FORCEPROP 2 LAST CDS_LIB standard
J 0
(4850 1950);
DISPLAY INVISIBLE (4850 1950);
FORCEADD OFFPAGE..1
(-2125 750);
FORCEPROP 2 LAST $XR1 34 
J 0
(-2466 750);
DISPLAY 0.638298 (-2466 750);
PAINT MONO (-2466 750);
FORCEPROP 2 LAST $XR0 12 
J 0
(-2376 750);
DISPLAY 0.638298 (-2376 750);
PAINT MONO (-2376 750);
FORCEPROP 2 LAST PATH I12
J 0
(-2325 800);
DISPLAY 1.021277 (-2325 800);
DISPLAY INVISIBLE (-2325 800);
FORCEPROP 1 LAST COMMENT_BODY TRUE
J 0
(-2000 650);
DISPLAY 0.872340 (-2000 650);
PAINT PEACH (-2000 650);
DISPLAY INVISIBLE (-2000 650);
FORCEPROP 1 LAST OFFPAGE TRUE
J 0
(-1800 625);
DISPLAY 0.872340 (-1800 625);
PAINT GREEN (-1800 625);
DISPLAY INVISIBLE (-1800 625);
FORCEPROP 2 LAST CDS_LIB standard
J 0
(-2125 750);
DISPLAY INVISIBLE (-2125 750);
FORCEADD OFFPAGE..2
(5300 1050);
FORCEPROP 2 LAST $XR1 10 
J 0
(5579 1050);
DISPLAY 0.638298 (5579 1050);
PAINT MONO (5579 1050);
FORCEPROP 2 LAST $XR0 27 
J 0
(5489 1050);
DISPLAY 0.638298 (5489 1050);
PAINT MONO (5489 1050);
FORCEPROP 2 LAST PATH I120
J 0
(5600 1100);
DISPLAY 1.021277 (5600 1100);
DISPLAY INVISIBLE (5600 1100);
FORCEPROP 1 LAST COMMENT_BODY TRUE
J 0
(5255 955);
DISPLAY 0.872340 (5255 955);
PAINT PEACH (5255 955);
DISPLAY INVISIBLE (5255 955);
FORCEPROP 1 LAST OFFPAGE TRUE
J 0
(5625 925);
DISPLAY 0.872340 (5625 925);
PAINT GREEN (5625 925);
DISPLAY INVISIBLE (5625 925);
FORCEPROP 2 LAST CDS_LIB standard
J 0
(5300 1050);
DISPLAY INVISIBLE (5300 1050);
FORCEADD OFFPAGE..3
(5300 1000);
FORCEPROP 2 LAST $XR1 27 
J 0
(5604 1000);
DISPLAY 0.638298 (5604 1000);
PAINT MONO (5604 1000);
FORCEPROP 2 LAST $XR0 10 
J 0
(5514 1000);
DISPLAY 0.638298 (5514 1000);
PAINT MONO (5514 1000);
FORCEPROP 2 LAST PATH I121
J 0
(5575 1050);
DISPLAY 1.021277 (5575 1050);
DISPLAY INVISIBLE (5575 1050);
FORCEPROP 1 LAST COMMENT_BODY TRUE
J 0
(5250 900);
DISPLAY 0.872340 (5250 900);
PAINT PEACH (5250 900);
DISPLAY INVISIBLE (5250 900);
FORCEPROP 1 LAST OFFPAGE TRUE
J 0
(5625 875);
DISPLAY 0.872340 (5625 875);
PAINT GREEN (5625 875);
DISPLAY INVISIBLE (5625 875);
FORCEPROP 2 LAST CDS_LIB standard
J 0
(5300 1000);
DISPLAY INVISIBLE (5300 1000);
FORCEADD OFFPAGE..3
(5300 1100);
FORCEPROP 2 LAST $XR0 12 
J 0
(5514 1100);
DISPLAY 0.638298 (5514 1100);
PAINT MONO (5514 1100);
FORCEPROP 2 LAST $XR1 27 
J 0
(5604 1100);
DISPLAY 0.638298 (5604 1100);
PAINT MONO (5604 1100);
FORCEPROP 2 LAST PATH I123
J 0
(5575 1150);
DISPLAY 1.021277 (5575 1150);
DISPLAY INVISIBLE (5575 1150);
FORCEPROP 1 LAST COMMENT_BODY TRUE
J 0
(5250 1000);
DISPLAY 0.872340 (5250 1000);
PAINT PEACH (5250 1000);
DISPLAY INVISIBLE (5250 1000);
FORCEPROP 1 LAST OFFPAGE TRUE
J 0
(5625 975);
DISPLAY 0.872340 (5625 975);
PAINT GREEN (5625 975);
DISPLAY INVISIBLE (5625 975);
FORCEPROP 2 LAST CDS_LIB standard
J 0
(5300 1100);
DISPLAY INVISIBLE (5300 1100);
FORCEADD OFFPAGE..3
(5300 1200);
FORCEPROP 2 LAST $XR1 27 
J 0
(5604 1200);
DISPLAY 0.638298 (5604 1200);
PAINT MONO (5604 1200);
FORCEPROP 2 LAST $XR0 10 
J 0
(5514 1200);
DISPLAY 0.638298 (5514 1200);
PAINT MONO (5514 1200);
FORCEPROP 2 LAST PATH I124
J 0
(5575 1250);
DISPLAY 1.021277 (5575 1250);
DISPLAY INVISIBLE (5575 1250);
FORCEPROP 1 LAST COMMENT_BODY TRUE
J 0
(5250 1100);
DISPLAY 0.872340 (5250 1100);
PAINT PEACH (5250 1100);
DISPLAY INVISIBLE (5250 1100);
FORCEPROP 1 LAST OFFPAGE TRUE
J 0
(5625 1075);
DISPLAY 0.872340 (5625 1075);
PAINT GREEN (5625 1075);
DISPLAY INVISIBLE (5625 1075);
FORCEPROP 2 LAST CDS_LIB standard
J 0
(5300 1200);
DISPLAY INVISIBLE (5300 1200);
FORCEADD OFFPAGE..2
(5300 1250);
FORCEPROP 2 LAST $XR1 10 
J 0
(5579 1250);
DISPLAY 0.638298 (5579 1250);
PAINT MONO (5579 1250);
FORCEPROP 2 LAST $XR0 27 
J 0
(5489 1250);
DISPLAY 0.638298 (5489 1250);
PAINT MONO (5489 1250);
FORCEPROP 2 LAST PATH I125
J 0
(5600 1300);
DISPLAY 1.021277 (5600 1300);
DISPLAY INVISIBLE (5600 1300);
FORCEPROP 1 LAST COMMENT_BODY TRUE
J 0
(5255 1155);
DISPLAY 0.872340 (5255 1155);
PAINT PEACH (5255 1155);
DISPLAY INVISIBLE (5255 1155);
FORCEPROP 1 LAST OFFPAGE TRUE
J 0
(5625 1125);
DISPLAY 0.872340 (5625 1125);
PAINT GREEN (5625 1125);
DISPLAY INVISIBLE (5625 1125);
FORCEPROP 2 LAST CDS_LIB standard
J 0
(5300 1250);
DISPLAY INVISIBLE (5300 1250);
FORCEADD OFFPAGE..3
(5300 1300);
FORCEPROP 2 LAST $XR1 27 
J 0
(5604 1300);
DISPLAY 0.638298 (5604 1300);
PAINT MONO (5604 1300);
FORCEPROP 2 LAST $XR0 12 
J 0
(5514 1300);
DISPLAY 0.638298 (5514 1300);
PAINT MONO (5514 1300);
FORCEPROP 2 LAST PATH I126
J 0
(5675 1350);
DISPLAY 1.021277 (5675 1350);
DISPLAY INVISIBLE (5675 1350);
FORCEPROP 1 LAST COMMENT_BODY TRUE
J 0
(5250 1200);
DISPLAY 0.872340 (5250 1200);
PAINT PEACH (5250 1200);
DISPLAY INVISIBLE (5250 1200);
FORCEPROP 1 LAST OFFPAGE TRUE
J 0
(5625 1175);
DISPLAY 0.872340 (5625 1175);
PAINT GREEN (5625 1175);
DISPLAY INVISIBLE (5625 1175);
FORCEPROP 2 LAST CDS_LIB standard
J 0
(5300 1300);
DISPLAY INVISIBLE (5300 1300);
FORCEADD OFFPAGE..2
(5300 1550);
FORCEPROP 2 LAST $XR1 10 
J 0
(5579 1550);
DISPLAY 0.638298 (5579 1550);
PAINT MONO (5579 1550);
FORCEPROP 2 LAST $XR0 27 
J 0
(5489 1550);
DISPLAY 0.638298 (5489 1550);
PAINT MONO (5489 1550);
FORCEPROP 2 LAST PATH I128
J 0
(5600 1600);
DISPLAY 1.021277 (5600 1600);
DISPLAY INVISIBLE (5600 1600);
FORCEPROP 1 LAST COMMENT_BODY TRUE
J 0
(5255 1455);
DISPLAY 0.872340 (5255 1455);
PAINT PEACH (5255 1455);
DISPLAY INVISIBLE (5255 1455);
FORCEPROP 1 LAST OFFPAGE TRUE
J 0
(5625 1425);
DISPLAY 0.872340 (5625 1425);
PAINT GREEN (5625 1425);
DISPLAY INVISIBLE (5625 1425);
FORCEPROP 2 LAST CDS_LIB standard
J 0
(5300 1550);
DISPLAY INVISIBLE (5300 1550);
FORCEADD OFFPAGE..3
(5300 1500);
FORCEPROP 2 LAST $XR1 27 
J 0
(5604 1500);
DISPLAY 0.638298 (5604 1500);
PAINT MONO (5604 1500);
FORCEPROP 2 LAST $XR0 10 
J 0
(5514 1500);
DISPLAY 0.638298 (5514 1500);
PAINT MONO (5514 1500);
FORCEPROP 2 LAST PATH I129
J 0
(5575 1550);
DISPLAY 1.021277 (5575 1550);
DISPLAY INVISIBLE (5575 1550);
FORCEPROP 1 LAST COMMENT_BODY TRUE
J 0
(5250 1400);
DISPLAY 0.872340 (5250 1400);
PAINT PEACH (5250 1400);
DISPLAY INVISIBLE (5250 1400);
FORCEPROP 1 LAST OFFPAGE TRUE
J 0
(5625 1375);
DISPLAY 0.872340 (5625 1375);
PAINT GREEN (5625 1375);
DISPLAY INVISIBLE (5625 1375);
FORCEPROP 2 LAST CDS_LIB standard
J 0
(5300 1500);
DISPLAY INVISIBLE (5300 1500);
FORCEADD OFFPAGE..3
(5300 1800);
FORCEPROP 2 LAST $XR1 27 
J 0
(5604 1800);
DISPLAY 0.638298 (5604 1800);
PAINT MONO (5604 1800);
FORCEPROP 2 LAST $XR0 10 
J 0
(5514 1800);
DISPLAY 0.638298 (5514 1800);
PAINT MONO (5514 1800);
FORCEPROP 2 LAST PATH I134
J 0
(5575 1850);
DISPLAY 1.021277 (5575 1850);
DISPLAY INVISIBLE (5575 1850);
FORCEPROP 1 LAST COMMENT_BODY TRUE
J 0
(5250 1700);
DISPLAY 0.872340 (5250 1700);
PAINT PEACH (5250 1700);
DISPLAY INVISIBLE (5250 1700);
FORCEPROP 1 LAST OFFPAGE TRUE
J 0
(5625 1675);
DISPLAY 0.872340 (5625 1675);
PAINT GREEN (5625 1675);
DISPLAY INVISIBLE (5625 1675);
FORCEPROP 2 LAST CDS_LIB standard
J 0
(5300 1800);
DISPLAY INVISIBLE (5300 1800);
FORCEADD OFFPAGE..2
(5300 1850);
FORCEPROP 2 LAST $XR1 10 
J 0
(5579 1850);
DISPLAY 0.638298 (5579 1850);
PAINT MONO (5579 1850);
FORCEPROP 2 LAST $XR0 27 
J 0
(5489 1850);
DISPLAY 0.638298 (5489 1850);
PAINT MONO (5489 1850);
FORCEPROP 2 LAST PATH I135
J 0
(5600 1900);
DISPLAY 1.021277 (5600 1900);
DISPLAY INVISIBLE (5600 1900);
FORCEPROP 1 LAST COMMENT_BODY TRUE
J 0
(5255 1755);
DISPLAY 0.872340 (5255 1755);
PAINT PEACH (5255 1755);
DISPLAY INVISIBLE (5255 1755);
FORCEPROP 1 LAST OFFPAGE TRUE
J 0
(5625 1725);
DISPLAY 0.872340 (5625 1725);
PAINT GREEN (5625 1725);
DISPLAY INVISIBLE (5625 1725);
FORCEPROP 2 LAST CDS_LIB standard
J 0
(5300 1850);
DISPLAY INVISIBLE (5300 1850);
FORCEADD OFFPAGE..3
(4850 2000);
FORCEPROP 2 LAST $XR0 10 
J 0
(5064 2000);
DISPLAY 0.638298 (5064 2000);
PAINT MONO (5064 2000);
FORCEPROP 2 LAST PATH I136
J 0
(5075 2050);
DISPLAY 1.021277 (5075 2050);
DISPLAY INVISIBLE (5075 2050);
FORCEPROP 1 LAST COMMENT_BODY TRUE
J 0
(4800 1900);
DISPLAY 0.872340 (4800 1900);
PAINT PEACH (4800 1900);
DISPLAY INVISIBLE (4800 1900);
FORCEPROP 1 LAST OFFPAGE TRUE
J 0
(5175 1875);
DISPLAY 0.872340 (5175 1875);
PAINT GREEN (5175 1875);
DISPLAY INVISIBLE (5175 1875);
FORCEPROP 2 LAST CDS_LIB standard
J 0
(4850 2000);
DISPLAY INVISIBLE (4850 2000);
FORCEADD OFFPAGE..3
(4850 2050);
FORCEPROP 2 LAST $XR0 10 
J 0
(5064 2050);
DISPLAY 0.638298 (5064 2050);
PAINT MONO (5064 2050);
FORCEPROP 2 LAST PATH I137
J 0
(5075 2100);
DISPLAY 1.021277 (5075 2100);
DISPLAY INVISIBLE (5075 2100);
FORCEPROP 1 LAST COMMENT_BODY TRUE
J 0
(4800 1950);
DISPLAY 0.872340 (4800 1950);
PAINT PEACH (4800 1950);
DISPLAY INVISIBLE (4800 1950);
FORCEPROP 1 LAST OFFPAGE TRUE
J 0
(5175 1925);
DISPLAY 0.872340 (5175 1925);
PAINT GREEN (5175 1925);
DISPLAY INVISIBLE (5175 1925);
FORCEPROP 2 LAST CDS_LIB standard
J 0
(4850 2050);
DISPLAY INVISIBLE (4850 2050);
FORCEADD OFFPAGE..3
(4850 2100);
FORCEPROP 2 LAST $XR0 10 
J 0
(5064 2100);
DISPLAY 0.638298 (5064 2100);
PAINT MONO (5064 2100);
FORCEPROP 2 LAST PATH I138
J 0
(5075 2150);
DISPLAY 1.021277 (5075 2150);
DISPLAY INVISIBLE (5075 2150);
FORCEPROP 1 LAST COMMENT_BODY TRUE
J 0
(4800 2000);
DISPLAY 0.872340 (4800 2000);
PAINT PEACH (4800 2000);
DISPLAY INVISIBLE (4800 2000);
FORCEPROP 1 LAST OFFPAGE TRUE
J 0
(5175 1975);
DISPLAY 0.872340 (5175 1975);
PAINT GREEN (5175 1975);
DISPLAY INVISIBLE (5175 1975);
FORCEPROP 2 LAST CDS_LIB standard
J 0
(4850 2100);
DISPLAY INVISIBLE (4850 2100);
FORCEADD OFFPAGE..2
(3700 3150);
FORCEPROP 2 LAST $XR0 20 
J 0
(3889 3150);
DISPLAY 0.638298 (3889 3150);
PAINT MONO (3889 3150);
FORCEPROP 2 LAST PATH I139
J 0
(3900 3200);
DISPLAY 1.021277 (3900 3200);
DISPLAY INVISIBLE (3900 3200);
FORCEPROP 1 LAST COMMENT_BODY TRUE
J 0
(3655 3055);
DISPLAY 0.872340 (3655 3055);
PAINT PEACH (3655 3055);
DISPLAY INVISIBLE (3655 3055);
FORCEPROP 1 LAST OFFPAGE TRUE
J 0
(4025 3025);
DISPLAY 0.872340 (4025 3025);
PAINT GREEN (4025 3025);
DISPLAY INVISIBLE (4025 3025);
FORCEPROP 2 LAST CDS_LIB standard
J 0
(3700 3150);
DISPLAY INVISIBLE (3700 3150);
FORCEADD OFFPAGE..2
(3700 3100);
FORCEPROP 2 LAST $XR0 20 
J 0
(3889 3100);
DISPLAY 0.638298 (3889 3100);
PAINT MONO (3889 3100);
FORCEPROP 2 LAST PATH I140
J 0
(3900 3150);
DISPLAY 1.021277 (3900 3150);
DISPLAY INVISIBLE (3900 3150);
FORCEPROP 1 LAST COMMENT_BODY TRUE
J 0
(3655 3005);
DISPLAY 0.872340 (3655 3005);
PAINT PEACH (3655 3005);
DISPLAY INVISIBLE (3655 3005);
FORCEPROP 1 LAST OFFPAGE TRUE
J 0
(4025 2975);
DISPLAY 0.872340 (4025 2975);
PAINT GREEN (4025 2975);
DISPLAY INVISIBLE (4025 2975);
FORCEPROP 2 LAST CDS_LIB standard
J 0
(3700 3100);
DISPLAY INVISIBLE (3700 3100);
FORCEADD OFFPAGE..2
(3700 3200);
FORCEPROP 2 LAST $XR0 20 
J 0
(3889 3200);
DISPLAY 0.638298 (3889 3200);
PAINT MONO (3889 3200);
FORCEPROP 2 LAST PATH I141
J 0
(3900 3250);
DISPLAY 1.021277 (3900 3250);
DISPLAY INVISIBLE (3900 3250);
FORCEPROP 1 LAST COMMENT_BODY TRUE
J 0
(3655 3105);
DISPLAY 0.872340 (3655 3105);
PAINT PEACH (3655 3105);
DISPLAY INVISIBLE (3655 3105);
FORCEPROP 1 LAST OFFPAGE TRUE
J 0
(4025 3075);
DISPLAY 0.872340 (4025 3075);
PAINT GREEN (4025 3075);
DISPLAY INVISIBLE (4025 3075);
FORCEPROP 2 LAST CDS_LIB standard
J 0
(3700 3200);
DISPLAY INVISIBLE (3700 3200);
FORCEADD OFFPAGE..2
(3700 3450);
FORCEPROP 2 LAST $XR0 20 
J 0
(3889 3450);
DISPLAY 0.638298 (3889 3450);
PAINT MONO (3889 3450);
FORCEPROP 2 LAST PATH I142
J 0
(3900 3500);
DISPLAY 1.021277 (3900 3500);
DISPLAY INVISIBLE (3900 3500);
FORCEPROP 1 LAST COMMENT_BODY TRUE
J 0
(3655 3355);
DISPLAY 0.872340 (3655 3355);
PAINT PEACH (3655 3355);
DISPLAY INVISIBLE (3655 3355);
FORCEPROP 1 LAST OFFPAGE TRUE
J 0
(4025 3325);
DISPLAY 0.872340 (4025 3325);
PAINT GREEN (4025 3325);
DISPLAY INVISIBLE (4025 3325);
FORCEPROP 2 LAST CDS_LIB standard
J 0
(3700 3450);
DISPLAY INVISIBLE (3700 3450);
FORCEADD OFFPAGE..2
(3700 3400);
FORCEPROP 2 LAST $XR0 20 
J 0
(3889 3400);
DISPLAY 0.638298 (3889 3400);
PAINT MONO (3889 3400);
FORCEPROP 2 LAST PATH I143
J 0
(3900 3450);
DISPLAY 1.021277 (3900 3450);
DISPLAY INVISIBLE (3900 3450);
FORCEPROP 1 LAST COMMENT_BODY TRUE
J 0
(3655 3305);
DISPLAY 0.872340 (3655 3305);
PAINT PEACH (3655 3305);
DISPLAY INVISIBLE (3655 3305);
FORCEPROP 1 LAST OFFPAGE TRUE
J 0
(4025 3275);
DISPLAY 0.872340 (4025 3275);
PAINT GREEN (4025 3275);
DISPLAY INVISIBLE (4025 3275);
FORCEPROP 2 LAST CDS_LIB standard
J 0
(3700 3400);
DISPLAY INVISIBLE (3700 3400);
FORCEADD OFFPAGE..2
(3700 3350);
FORCEPROP 2 LAST $XR0 20 
J 0
(3889 3350);
DISPLAY 0.638298 (3889 3350);
PAINT MONO (3889 3350);
FORCEPROP 2 LAST PATH I144
J 0
(3900 3400);
DISPLAY 1.021277 (3900 3400);
DISPLAY INVISIBLE (3900 3400);
FORCEPROP 1 LAST COMMENT_BODY TRUE
J 0
(3655 3255);
DISPLAY 0.872340 (3655 3255);
PAINT PEACH (3655 3255);
DISPLAY INVISIBLE (3655 3255);
FORCEPROP 1 LAST OFFPAGE TRUE
J 0
(4025 3225);
DISPLAY 0.872340 (4025 3225);
PAINT GREEN (4025 3225);
DISPLAY INVISIBLE (4025 3225);
FORCEPROP 2 LAST CDS_LIB standard
J 0
(3700 3350);
DISPLAY INVISIBLE (3700 3350);
FORCEADD OFFPAGE..2
(3700 3300);
FORCEPROP 2 LAST $XR0 20 
J 0
(3889 3300);
DISPLAY 0.638298 (3889 3300);
PAINT MONO (3889 3300);
FORCEPROP 2 LAST PATH I145
J 0
(3900 3350);
DISPLAY 1.021277 (3900 3350);
DISPLAY INVISIBLE (3900 3350);
FORCEPROP 1 LAST COMMENT_BODY TRUE
J 0
(3655 3205);
DISPLAY 0.872340 (3655 3205);
PAINT PEACH (3655 3205);
DISPLAY INVISIBLE (3655 3205);
FORCEPROP 1 LAST OFFPAGE TRUE
J 0
(4025 3175);
DISPLAY 0.872340 (4025 3175);
PAINT GREEN (4025 3175);
DISPLAY INVISIBLE (4025 3175);
FORCEPROP 2 LAST CDS_LIB standard
J 0
(3700 3300);
DISPLAY INVISIBLE (3700 3300);
FORCEADD OFFPAGE..2
(3700 3250);
FORCEPROP 2 LAST $XR0 20 
J 0
(3889 3250);
DISPLAY 0.638298 (3889 3250);
PAINT MONO (3889 3250);
FORCEPROP 2 LAST PATH I146
J 0
(3900 3300);
DISPLAY 1.021277 (3900 3300);
DISPLAY INVISIBLE (3900 3300);
FORCEPROP 1 LAST COMMENT_BODY TRUE
J 0
(3655 3155);
DISPLAY 0.872340 (3655 3155);
PAINT PEACH (3655 3155);
DISPLAY INVISIBLE (3655 3155);
FORCEPROP 1 LAST OFFPAGE TRUE
J 0
(4025 3125);
DISPLAY 0.872340 (4025 3125);
PAINT GREEN (4025 3125);
DISPLAY INVISIBLE (4025 3125);
FORCEPROP 2 LAST CDS_LIB standard
J 0
(3700 3250);
DISPLAY INVISIBLE (3700 3250);
FORCEADD OFFPAGE..2
(3700 3500);
FORCEPROP 2 LAST $XR0 20 
J 0
(3889 3500);
DISPLAY 0.638298 (3889 3500);
PAINT MONO (3889 3500);
FORCEPROP 2 LAST PATH I147
J 0
(3950 3550);
DISPLAY 1.021277 (3950 3550);
DISPLAY INVISIBLE (3950 3550);
FORCEPROP 1 LAST COMMENT_BODY TRUE
J 0
(3655 3405);
DISPLAY 0.872340 (3655 3405);
PAINT PEACH (3655 3405);
DISPLAY INVISIBLE (3655 3405);
FORCEPROP 1 LAST OFFPAGE TRUE
J 0
(4025 3375);
DISPLAY 0.872340 (4025 3375);
PAINT GREEN (4025 3375);
DISPLAY INVISIBLE (4025 3375);
FORCEPROP 2 LAST CDS_LIB standard
J 0
(3700 3500);
DISPLAY INVISIBLE (3700 3500);
FORCEADD OFFPAGE..2
(3700 3600);
FORCEPROP 2 LAST $XR0 20 
J 0
(3889 3600);
DISPLAY 0.638298 (3889 3600);
PAINT MONO (3889 3600);
FORCEPROP 2 LAST PATH I148
J 0
(3900 3650);
DISPLAY 1.021277 (3900 3650);
DISPLAY INVISIBLE (3900 3650);
FORCEPROP 1 LAST COMMENT_BODY TRUE
J 0
(3655 3505);
DISPLAY 0.872340 (3655 3505);
PAINT PEACH (3655 3505);
DISPLAY INVISIBLE (3655 3505);
FORCEPROP 1 LAST OFFPAGE TRUE
J 0
(4025 3475);
DISPLAY 0.872340 (4025 3475);
PAINT GREEN (4025 3475);
DISPLAY INVISIBLE (4025 3475);
FORCEPROP 2 LAST CDS_LIB standard
J 0
(3700 3600);
DISPLAY INVISIBLE (3700 3600);
FORCEADD OFFPAGE..2
(3700 3550);
FORCEPROP 2 LAST $XR0 20 
J 0
(3889 3550);
DISPLAY 0.638298 (3889 3550);
PAINT MONO (3889 3550);
FORCEPROP 2 LAST PATH I149
J 0
(3900 3600);
DISPLAY 1.021277 (3900 3600);
DISPLAY INVISIBLE (3900 3600);
FORCEPROP 1 LAST COMMENT_BODY TRUE
J 0
(3655 3455);
DISPLAY 0.872340 (3655 3455);
PAINT PEACH (3655 3455);
DISPLAY INVISIBLE (3655 3455);
FORCEPROP 1 LAST OFFPAGE TRUE
J 0
(4025 3425);
DISPLAY 0.872340 (4025 3425);
PAINT GREEN (4025 3425);
DISPLAY INVISIBLE (4025 3425);
FORCEPROP 2 LAST CDS_LIB standard
J 0
(3700 3550);
DISPLAY INVISIBLE (3700 3550);
FORCEADD TAP..1
(4175 3000);
FORCEPROP 3 LASTPIN (4125 3000) SIG_NAME M_BMC_DDR4_MA<1>
J 0
(4135 3010);
DISPLAY 0.659574 (4135 3010);
PAINT MONO (4135 3010);
DISPLAY INVISIBLE (4135 3010);
FORCEPROP 1 LASTPIN (4125 3000) BN 1
J 0
(4113 3008);
DISPLAY 0.702128 (4113 3008);
PAINT VIOLET (4113 3008);
FORCEPROP 1 LAST PATH I150
J 0
(4173 3000);
DISPLAY 0.872340 (4173 3000);
PAINT GREEN (4173 3000);
DISPLAY INVISIBLE (4173 3000);
FORCEPROP 1 LAST HDL_TAP TRUE
J 0
(4500 2875);
DISPLAY 0.872340 (4500 2875);
DISPLAY INVISIBLE (4500 2875);
FORCEPROP 1 LAST BODY_TYPE PLUMBING
J 0
(4175 3050);
DISPLAY 0.872340 (4175 3050);
PAINT GREEN (4175 3050);
DISPLAY INVISIBLE (4175 3050);
FORCEPROP 2 LAST CDS_LIB standard
J 0
(4175 3000);
DISPLAY INVISIBLE (4175 3000);
FORCEADD TAP..1
(4175 3050);
FORCEPROP 3 LASTPIN (4125 3050) SIG_NAME M_BMC_DDR4_MA<0>
J 0
(4135 3060);
DISPLAY 0.659574 (4135 3060);
PAINT MONO (4135 3060);
DISPLAY INVISIBLE (4135 3060);
FORCEPROP 1 LASTPIN (4125 3050) BN 0
J 0
(4113 3058);
DISPLAY 0.702128 (4113 3058);
PAINT VIOLET (4113 3058);
FORCEPROP 1 LAST PATH I151
J 0
(4173 3050);
DISPLAY 0.872340 (4173 3050);
PAINT GREEN (4173 3050);
DISPLAY INVISIBLE (4173 3050);
FORCEPROP 1 LAST HDL_TAP TRUE
J 0
(4500 2925);
DISPLAY 0.872340 (4500 2925);
DISPLAY INVISIBLE (4500 2925);
FORCEPROP 1 LAST BODY_TYPE PLUMBING
J 0
(4175 3100);
DISPLAY 0.872340 (4175 3100);
PAINT GREEN (4175 3100);
DISPLAY INVISIBLE (4175 3100);
FORCEPROP 2 LAST CDS_LIB standard
J 0
(4175 3050);
DISPLAY INVISIBLE (4175 3050);
FORCEADD Q_CAP..2
(3825 4600);
FORCEPROP 1 LAST TOLERANCE 10%
J 2
(4425 4675);
DISPLAY 0.510638 (4425 4675);
PAINT SKYBLUE (4425 4675);
FORCEPROP 1 LAST PART_NUMBER CH4104K1B00
J 1
(4150 4725);
DISPLAY 0.510638 (4150 4725);
PAINT WHITE (4150 4725);
FORCEPROP 1 LAST VOLTAGE 25V
J 0
(4225 4675);
DISPLAY 0.510638 (4225 4675);
PAINT SKYBLUE (4225 4675);
FORCEPROP 1 LAST MATERIAL X7R
J 0
(4100 4675);
DISPLAY 0.510638 (4100 4675);
PAINT SKYBLUE (4100 4675);
FORCEPROP 1 LAST VALUE 0.1UF
J 2
(4125 4600);
DISPLAY 0.510638 (4125 4600);
PAINT SKYBLUE (4125 4600);
FORCEPROP 1 LAST PACK_TYPE 0402
J 1
(4025 4675);
DISPLAY 0.510638 (4025 4675);
PAINT SKYBLUE (4025 4675);
FORCEPROP 1 LAST PATH I152
J 0
(3825 4800);
DISPLAY 0.978723 (3825 4800);
PAINT WHITE (3825 4800);
DISPLAY INVISIBLE (3825 4800);
FORCEPROP 2 LAST CDS_LIB pure_quanta
J 0
(3825 4600);
DISPLAY INVISIBLE (3825 4600);
FORCEPROP 1 LAST LOCATION C24
J 1
(3675 4600);
DISPLAY 0.702128 (3675 4600);
PAINT YELLOW (3675 4600);
FORCEPROP 1 LASTPIN (3725 4600) $PN 1
J 0
(3715 4615);
DISPLAY 0.808511 (3715 4615);
PAINT WHITE (3715 4615);
FORCEPROP 1 LASTPIN (3925 4600) $PN 2
J 0
(3910 4615);
DISPLAY 0.808511 (3910 4615);
PAINT WHITE (3910 4615);
FORCEPROP 2 LAST $SEC 1
J 0
(3825 4850);
DISPLAY 0.680851 (3825 4850);
PAINT MONO (3825 4850);
DISPLAY INVISIBLE (3825 4850);
FORCEPROP 0 LAST CDS_SEC 1
J 0
(3825 4850);
DISPLAY 0.680851 (3825 4850);
PAINT MONO (3825 4850);
DISPLAY INVISIBLE (3825 4850);
FORCEADD Q_CAP..2
(3825 4550);
FORCEPROP 1 LAST VALUE 0.1UF
J 2
(4125 4550);
DISPLAY 0.510638 (4125 4550);
PAINT SKYBLUE (4125 4550);
FORCEPROP 1 LAST PATH I153
J 0
(3825 4750);
DISPLAY 0.978723 (3825 4750);
PAINT WHITE (3825 4750);
DISPLAY INVISIBLE (3825 4750);
FORCEPROP 1 LAST PACK_TYPE 0402
J 1
(3825 4350);
DISPLAY 0.510638 (3825 4350);
PAINT SKYBLUE (3825 4350);
DISPLAY INVISIBLE (3825 4350);
FORCEPROP 2 LAST CDS_LIB pure_quanta
J 0
(3825 4550);
DISPLAY INVISIBLE (3825 4550);
FORCEPROP 1 LAST VOLTAGE 25V
J 0
(3825 4450);
DISPLAY 0.510638 (3825 4450);
PAINT SKYBLUE (3825 4450);
DISPLAY INVISIBLE (3825 4450);
FORCEPROP 1 LAST TOLERANCE 10%
J 2
(3825 4400);
DISPLAY 0.510638 (3825 4400);
PAINT SKYBLUE (3825 4400);
DISPLAY INVISIBLE (3825 4400);
FORCEPROP 1 LAST PART_NUMBER CH4104K1B00
J 1
(4025 4625);
DISPLAY 0.510638 (4025 4625);
PAINT WHITE (4025 4625);
DISPLAY INVISIBLE (4025 4625);
FORCEPROP 1 LAST MATERIAL X7R
J 0
(3825 4400);
DISPLAY 0.510638 (3825 4400);
PAINT SKYBLUE (3825 4400);
DISPLAY INVISIBLE (3825 4400);
FORCEPROP 1 LAST LOCATION C25
J 1
(3675 4550);
DISPLAY 0.702128 (3675 4550);
PAINT YELLOW (3675 4550);
FORCEPROP 1 LASTPIN (3725 4550) $PN 1
J 0
(3715 4565);
DISPLAY 0.808511 (3715 4565);
PAINT WHITE (3715 4565);
FORCEPROP 1 LASTPIN (3925 4550) $PN 2
J 0
(3910 4565);
DISPLAY 0.808511 (3910 4565);
PAINT WHITE (3910 4565);
FORCEPROP 2 LAST $SEC 1
J 0
(3825 4800);
DISPLAY 0.680851 (3825 4800);
PAINT MONO (3825 4800);
DISPLAY INVISIBLE (3825 4800);
FORCEPROP 0 LAST CDS_SEC 1
J 0
(3825 4800);
DISPLAY 0.680851 (3825 4800);
PAINT MONO (3825 4800);
DISPLAY INVISIBLE (3825 4800);
FORCEADD OFFPAGE..3
(5050 3125);
FORCEPROP 2 LAST $XR0 20 
J 0
(5264 3125);
DISPLAY 0.638298 (5264 3125);
PAINT MONO (5264 3125);
FORCEPROP 2 LAST PATH I154
J 0
(5275 3175);
DISPLAY 1.021277 (5275 3175);
DISPLAY INVISIBLE (5275 3175);
FORCEPROP 1 LAST COMMENT_BODY TRUE
J 0
(5000 3025);
DISPLAY 0.872340 (5000 3025);
PAINT PEACH (5000 3025);
DISPLAY INVISIBLE (5000 3025);
FORCEPROP 1 LAST OFFPAGE TRUE
J 0
(5375 3000);
DISPLAY 0.872340 (5375 3000);
PAINT GREEN (5375 3000);
DISPLAY INVISIBLE (5375 3000);
FORCEPROP 2 LAST CDS_LIB standard
J 0
(5050 3125);
DISPLAY INVISIBLE (5050 3125);
FORCEADD OFFPAGE..2
(4800 4550);
FORCEPROP 2 LAST $XR0 10 
J 0
(4989 4550);
DISPLAY 0.638298 (4989 4550);
PAINT MONO (4989 4550);
FORCEPROP 2 LAST CDS_LIB standard
J 0
(4800 4550);
DISPLAY INVISIBLE (4800 4550);
FORCEPROP 2 LAST PATH I155
J 0
(5000 4600);
DISPLAY 1.021277 (5000 4600);
DISPLAY INVISIBLE (5000 4600);
FORCEPROP 1 LAST OFFPAGE TRUE
J 0
(5125 4425);
DISPLAY 0.872340 (5125 4425);
PAINT GREEN (5125 4425);
DISPLAY INVISIBLE (5125 4425);
FORCEPROP 1 LAST COMMENT_BODY TRUE
J 0
(4755 4455);
DISPLAY 0.872340 (4755 4455);
PAINT PEACH (4755 4455);
DISPLAY INVISIBLE (4755 4455);
FORCEADD OFFPAGE..2
(4800 4600);
FORCEPROP 2 LAST $XR0 10 
J 0
(4989 4600);
DISPLAY 0.638298 (4989 4600);
PAINT MONO (4989 4600);
FORCEPROP 2 LAST CDS_LIB standard
J 0
(4800 4600);
DISPLAY INVISIBLE (4800 4600);
FORCEPROP 2 LAST PATH I156
J 0
(5000 4650);
DISPLAY 1.021277 (5000 4650);
DISPLAY INVISIBLE (5000 4650);
FORCEPROP 1 LAST OFFPAGE TRUE
J 0
(5125 4475);
DISPLAY 0.872340 (5125 4475);
PAINT GREEN (5125 4475);
DISPLAY INVISIBLE (5125 4475);
FORCEPROP 1 LAST COMMENT_BODY TRUE
J 0
(4755 4505);
DISPLAY 0.872340 (4755 4505);
PAINT PEACH (4755 4505);
DISPLAY INVISIBLE (4755 4505);
FORCEADD Q_RES..1
(-1475 -425);
FORCEPROP 1 LAST VALUE 4.7K
J 2
(-1600 -425);
DISPLAY 0.510638 (-1600 -425);
PAINT SKYBLUE (-1600 -425);
FORCEPROP 1 LAST MATERIAL EMPTY
J 0
(-1350 -425);
DISPLAY 0.510638 (-1350 -425);
PAINT RED (-1350 -425);
FORCEPROP 1 LAST PART_NUMBER CS24702FB06
J 0
(-1525 -325);
DISPLAY 0.510638 (-1525 -325);
PAINT WHITE (-1525 -325);
DISPLAY INVISIBLE (-1525 -325);
FORCEPROP 2 LAST CDS_LIB pure_quanta
J 0
(-1475 -425);
DISPLAY INVISIBLE (-1475 -425);
FORCEPROP 1 LAST TOLERANCE 1%
J 0
(-1475 -525);
DISPLAY 0.510638 (-1475 -525);
PAINT SKYBLUE (-1475 -525);
DISPLAY INVISIBLE (-1475 -525);
FORCEPROP 1 LAST PATH I2
J 0
(-1525 -275);
DISPLAY 0.978723 (-1525 -275);
PAINT WHITE (-1525 -275);
DISPLAY INVISIBLE (-1525 -275);
FORCEPROP 1 LAST WATTAGE 1/16W
J 2
(-1500 -575);
DISPLAY 0.510638 (-1500 -575);
PAINT SKYBLUE (-1500 -575);
DISPLAY INVISIBLE (-1500 -575);
FORCEPROP 1 LAST PACK_TYPE 0402LF
J 0
(-1225 -575);
DISPLAY 0.510638 (-1225 -575);
PAINT SKYBLUE (-1225 -575);
DISPLAY INVISIBLE (-1225 -575);
FORCEPROP 1 LAST LOCATION R117
J 0
(-1825 -425);
DISPLAY 0.702128 (-1825 -425);
PAINT YELLOW (-1825 -425);
FORCEPROP 0 LAST $SEC 1
J 0
(-1825 -375);
DISPLAY INVISIBLE (-1825 -375);
FORCEPROP 0 LAST CDS_SEC 1
J 0
(-1825 -375);
DISPLAY INVISIBLE (-1825 -375);
FORCEPROP 1 LASTPIN (-1575 -425) $PN 1
J 0
(-1563 -413);
DISPLAY 0.808511 (-1563 -413);
PAINT WHITE (-1563 -413);
DISPLAY INVISIBLE (-1563 -413);
FORCEPROP 1 LASTPIN (-1375 -425) $PN 2
J 0
(-1413 -413);
DISPLAY 0.808511 (-1413 -413);
PAINT WHITE (-1413 -413);
DISPLAY INVISIBLE (-1413 -413);
FORCEADD OFFPAGE..6
(-2325 2000);
FORCEPROP 2 LAST $XR1 12 
J 0
(-2694 2000);
DISPLAY 0.638298 (-2694 2000);
PAINT MONO (-2694 2000);
FORCEPROP 2 LAST $XR0 10 
J 0
(-2604 2000);
DISPLAY 0.638298 (-2604 2000);
PAINT MONO (-2604 2000);
FORCEPROP 2 LAST PATH I21
J 0
(-2525 2050);
DISPLAY 1.021277 (-2525 2050);
DISPLAY INVISIBLE (-2525 2050);
FORCEPROP 1 LAST COMMENT_BODY TRUE
J 0
(-2225 1925);
DISPLAY 0.872340 (-2225 1925);
PAINT PEACH (-2225 1925);
DISPLAY INVISIBLE (-2225 1925);
FORCEPROP 1 LAST OFFPAGE TRUE
J 0
(-2000 1875);
DISPLAY 0.872340 (-2000 1875);
PAINT GREEN (-2000 1875);
DISPLAY INVISIBLE (-2000 1875);
FORCEPROP 2 LAST CDS_LIB standard
J 0
(-2325 2000);
DISPLAY INVISIBLE (-2325 2000);
FORCEADD Q_RES..1
(4125 1050);
FORCEPROP 1 LAST MATERIAL CHIP
J 2
(4500 1050);
DISPLAY 0.510638 (4500 1050);
PAINT SKYBLUE (4500 1050);
FORCEPROP 1 LAST VALUE 33.2
J 0
(4250 1050);
DISPLAY 0.510638 (4250 1050);
PAINT SKYBLUE (4250 1050);
FORCEPROP 1 LAST PACK_TYPE 0402LF
J 0
(4375 900);
DISPLAY 0.510638 (4375 900);
PAINT SKYBLUE (4375 900);
DISPLAY INVISIBLE (4375 900);
FORCEPROP 1 LAST WATTAGE 1/16W
J 2
(4100 900);
DISPLAY 0.510638 (4100 900);
PAINT SKYBLUE (4100 900);
DISPLAY INVISIBLE (4100 900);
FORCEPROP 1 LAST PATH I235
J 0
(4075 1200);
DISPLAY 0.978723 (4075 1200);
PAINT WHITE (4075 1200);
DISPLAY INVISIBLE (4075 1200);
FORCEPROP 2 LAST CDS_LIB pure_quanta
J 0
(4125 1050);
DISPLAY INVISIBLE (4125 1050);
FORCEPROP 1 LAST PART_NUMBER CS03322FB03
J 0
(4075 1150);
DISPLAY 0.510638 (4075 1150);
PAINT WHITE (4075 1150);
DISPLAY INVISIBLE (4075 1150);
FORCEPROP 1 LAST TOLERANCE 1%
J 0
(4250 1050);
DISPLAY 0.510638 (4250 1050);
PAINT SKYBLUE (4250 1050);
DISPLAY INVISIBLE (4250 1050);
FORCEPROP 1 LAST LOCATION R146
J 2
(3950 1050);
DISPLAY 0.702128 (3950 1050);
PAINT YELLOW (3950 1050);
FORCEPROP 0 LAST $SEC 1
J 0
(3875 1100);
DISPLAY 0.680851 (3875 1100);
PAINT MONO (3875 1100);
DISPLAY INVISIBLE (3875 1100);
FORCEPROP 0 LAST CDS_SEC 1
J 0
(3875 1100);
DISPLAY 1.021277 (3875 1100);
DISPLAY INVISIBLE (3875 1100);
FORCEPROP 1 LASTPIN (4025 1050) $PN 1
J 0
(4037 1062);
DISPLAY 0.808511 (4037 1062);
PAINT WHITE (4037 1062);
DISPLAY INVISIBLE (4037 1062);
FORCEPROP 1 LASTPIN (4225 1050) $PN 2
J 0
(4187 1062);
DISPLAY 0.808511 (4187 1062);
PAINT WHITE (4187 1062);
DISPLAY INVISIBLE (4187 1062);
FORCEADD Q_RES..1
(4125 1000);
FORCEPROP 1 LAST VALUE 33.2
J 0
(4250 1000);
DISPLAY 0.510638 (4250 1000);
PAINT SKYBLUE (4250 1000);
FORCEPROP 1 LAST MATERIAL CHIP
J 2
(4500 1000);
DISPLAY 0.510638 (4500 1000);
PAINT SKYBLUE (4500 1000);
FORCEPROP 1 LAST PACK_TYPE 0402LF
J 0
(4375 850);
DISPLAY 0.510638 (4375 850);
PAINT SKYBLUE (4375 850);
DISPLAY INVISIBLE (4375 850);
FORCEPROP 1 LAST WATTAGE 1/16W
J 2
(4100 850);
DISPLAY 0.510638 (4100 850);
PAINT SKYBLUE (4100 850);
DISPLAY INVISIBLE (4100 850);
FORCEPROP 1 LAST PATH I236
J 0
(4075 1150);
DISPLAY 0.978723 (4075 1150);
PAINT WHITE (4075 1150);
DISPLAY INVISIBLE (4075 1150);
FORCEPROP 2 LAST CDS_LIB pure_quanta
J 0
(4125 1000);
DISPLAY INVISIBLE (4125 1000);
FORCEPROP 1 LAST PART_NUMBER CS03322FB03
J 0
(4075 1100);
DISPLAY 0.510638 (4075 1100);
PAINT WHITE (4075 1100);
DISPLAY INVISIBLE (4075 1100);
FORCEPROP 1 LAST TOLERANCE 1%
J 0
(4250 1000);
DISPLAY 0.510638 (4250 1000);
PAINT SKYBLUE (4250 1000);
DISPLAY INVISIBLE (4250 1000);
FORCEPROP 1 LAST LOCATION R147
J 2
(3950 1000);
DISPLAY 0.702128 (3950 1000);
PAINT YELLOW (3950 1000);
FORCEPROP 1 LASTPIN (4025 1000) $PN 1
J 0
(4037 1012);
DISPLAY 0.808511 (4037 1012);
PAINT WHITE (4037 1012);
FORCEPROP 1 LASTPIN (4225 1000) $PN 2
J 0
(4187 1012);
DISPLAY 0.808511 (4187 1012);
PAINT WHITE (4187 1012);
FORCEPROP 0 LAST $SEC 1
J 0
(4225 1050);
DISPLAY 0.680851 (4225 1050);
PAINT MONO (4225 1050);
DISPLAY INVISIBLE (4225 1050);
FORCEPROP 0 LAST CDS_SEC 1
J 0
(4225 1050);
DISPLAY 0.680851 (4225 1050);
DISPLAY INVISIBLE (4225 1050);
FORCEADD Q_CAP..1
(-2200 2625);
FORCEPROP 1 LAST TOLERANCE 10%
J 0
(-2150 2575);
DISPLAY 0.510638 (-2150 2575);
PAINT SKYBLUE (-2150 2575);
FORCEPROP 1 LAST VOLTAGE 50V
J 0
(-2150 2625);
DISPLAY 0.510638 (-2150 2625);
PAINT SKYBLUE (-2150 2625);
FORCEPROP 1 LAST MATERIAL EMPTY
J 0
(-2150 2525);
DISPLAY 0.510638 (-2150 2525);
PAINT RED (-2150 2525);
FORCEPROP 1 LAST PACK_TYPE C0402
J 0
(-2150 2475);
DISPLAY 0.510638 (-2150 2475);
PAINT SKYBLUE (-2150 2475);
FORCEPROP 1 LAST PART_NUMBER CH31006KB18
J 0
(-2150 2425);
DISPLAY 0.510638 (-2150 2425);
PAINT WHITE (-2150 2425);
FORCEPROP 1 LAST VALUE 0.01UF
J 0
(-2150 2675);
DISPLAY 0.510638 (-2150 2675);
PAINT SKYBLUE (-2150 2675);
FORCEPROP 1 LAST PATH I24
J 0
(-2150 2775);
DISPLAY 0.978723 (-2150 2775);
PAINT WHITE (-2150 2775);
DISPLAY INVISIBLE (-2150 2775);
FORCEPROP 2 LAST CDS_LIB pure_quanta
J 0
(-2200 2625);
DISPLAY INVISIBLE (-2200 2625);
FORCEPROP 1 LAST LOCATION C21
J 0
(-2150 2725);
DISPLAY 0.702128 (-2150 2725);
PAINT YELLOW (-2150 2725);
FORCEPROP 1 LASTPIN (-2200 2725) $PN 1
J 0
(-2190 2705);
DISPLAY 0.808511 (-2190 2705);
PAINT WHITE (-2190 2705);
FORCEPROP 1 LASTPIN (-2200 2525) $PN 2
J 0
(-2190 2505);
DISPLAY 0.808511 (-2190 2505);
PAINT WHITE (-2190 2505);
FORCEPROP 2 LAST $SEC 1
J 0
(-2150 2825);
DISPLAY 0.680851 (-2150 2825);
PAINT MONO (-2150 2825);
DISPLAY INVISIBLE (-2150 2825);
FORCEPROP 0 LAST CDS_SEC 1
J 0
(-2150 2825);
DISPLAY 0.680851 (-2150 2825);
PAINT MONO (-2150 2825);
DISPLAY INVISIBLE (-2150 2825);
FORCEADD Q_RES..1
(-650 250);
FORCEPROP 1 LAST VALUE 33.2
J 0
(-525 250);
DISPLAY 0.510638 (-525 250);
PAINT SKYBLUE (-525 250);
FORCEPROP 1 LAST MATERIAL CHIP
J 2
(-275 250);
DISPLAY 0.510638 (-275 250);
PAINT SKYBLUE (-275 250);
FORCEPROP 1 LAST PACK_TYPE 0402LF
J 0
(-400 100);
DISPLAY 0.510638 (-400 100);
PAINT SKYBLUE (-400 100);
DISPLAY INVISIBLE (-400 100);
FORCEPROP 1 LAST WATTAGE 1/16W
J 2
(-675 100);
DISPLAY 0.510638 (-675 100);
PAINT SKYBLUE (-675 100);
DISPLAY INVISIBLE (-675 100);
FORCEPROP 1 LAST PATH I244
J 0
(-700 400);
DISPLAY 0.978723 (-700 400);
PAINT WHITE (-700 400);
DISPLAY INVISIBLE (-700 400);
FORCEPROP 2 LAST CDS_LIB pure_quanta
J 0
(-650 250);
DISPLAY INVISIBLE (-650 250);
FORCEPROP 1 LAST PART_NUMBER CS03322FB03
J 0
(-700 350);
DISPLAY 0.510638 (-700 350);
PAINT WHITE (-700 350);
DISPLAY INVISIBLE (-700 350);
FORCEPROP 1 LAST TOLERANCE 1%
J 0
(-525 250);
DISPLAY 0.510638 (-525 250);
PAINT SKYBLUE (-525 250);
DISPLAY INVISIBLE (-525 250);
FORCEPROP 1 LAST LOCATION R236
J 2
(-825 250);
DISPLAY 0.702128 (-825 250);
PAINT YELLOW (-825 250);
FORCEPROP 1 LASTPIN (-750 250) $PN 1
J 0
(-738 262);
DISPLAY 0.808511 (-738 262);
PAINT WHITE (-738 262);
FORCEPROP 1 LASTPIN (-550 250) $PN 2
J 0
(-588 262);
DISPLAY 0.808511 (-588 262);
PAINT WHITE (-588 262);
FORCEPROP 0 LAST $SEC 1
J 0
(-550 300);
DISPLAY 0.680851 (-550 300);
PAINT MONO (-550 300);
DISPLAY INVISIBLE (-550 300);
FORCEPROP 0 LAST CDS_SEC 1
J 0
(-550 300);
DISPLAY 0.680851 (-550 300);
DISPLAY INVISIBLE (-550 300);
FORCEADD Q_RES..1
(-650 300);
FORCEPROP 1 LAST VALUE 33.2
J 0
(-525 300);
DISPLAY 0.510638 (-525 300);
PAINT SKYBLUE (-525 300);
FORCEPROP 1 LAST MATERIAL CHIP
J 2
(-275 300);
DISPLAY 0.510638 (-275 300);
PAINT SKYBLUE (-275 300);
FORCEPROP 1 LAST PACK_TYPE 0402LF
J 0
(-400 150);
DISPLAY 0.510638 (-400 150);
PAINT SKYBLUE (-400 150);
DISPLAY INVISIBLE (-400 150);
FORCEPROP 1 LAST WATTAGE 1/16W
J 2
(-675 150);
DISPLAY 0.510638 (-675 150);
PAINT SKYBLUE (-675 150);
DISPLAY INVISIBLE (-675 150);
FORCEPROP 1 LAST PATH I245
J 0
(-700 450);
DISPLAY 0.978723 (-700 450);
PAINT WHITE (-700 450);
DISPLAY INVISIBLE (-700 450);
FORCEPROP 2 LAST CDS_LIB pure_quanta
J 0
(-650 300);
DISPLAY INVISIBLE (-650 300);
FORCEPROP 1 LAST PART_NUMBER CS03322FB03
J 0
(-700 400);
DISPLAY 0.510638 (-700 400);
PAINT WHITE (-700 400);
DISPLAY INVISIBLE (-700 400);
FORCEPROP 1 LAST TOLERANCE 1%
J 0
(-525 300);
DISPLAY 0.510638 (-525 300);
PAINT SKYBLUE (-525 300);
DISPLAY INVISIBLE (-525 300);
FORCEPROP 1 LAST LOCATION R162
J 2
(-825 300);
DISPLAY 0.702128 (-825 300);
PAINT YELLOW (-825 300);
FORCEPROP 0 LAST $SEC 1
J 0
(-900 350);
DISPLAY 0.680851 (-900 350);
PAINT MONO (-900 350);
DISPLAY INVISIBLE (-900 350);
FORCEPROP 0 LAST CDS_SEC 1
J 0
(-900 350);
DISPLAY 1.021277 (-900 350);
DISPLAY INVISIBLE (-900 350);
FORCEPROP 1 LASTPIN (-750 300) $PN 1
J 0
(-738 312);
DISPLAY 0.808511 (-738 312);
PAINT WHITE (-738 312);
DISPLAY INVISIBLE (-738 312);
FORCEPROP 1 LASTPIN (-550 300) $PN 2
J 0
(-588 312);
DISPLAY 0.808511 (-588 312);
PAINT WHITE (-588 312);
DISPLAY INVISIBLE (-588 312);
FORCEADD OFFPAGE..2
R 2
(-2125 300);
FORCEPROP 2 LAST $XR1 28 
J 0
(-2469 300);
DISPLAY 0.638298 (-2469 300);
PAINT MONO (-2469 300);
FORCEPROP 2 LAST $XR0 27 
J 0
(-2379 300);
DISPLAY 0.638298 (-2379 300);
PAINT MONO (-2379 300);
FORCEPROP 2 LAST PATH I246
J 0
(-2075 375);
DISPLAY 1.021277 (-2075 375);
DISPLAY INVISIBLE (-2075 375);
FORCEPROP 1 LAST COMMENT_BODY TRUE
J 2
(-2080 205);
DISPLAY 0.872340 (-2080 205);
PAINT PEACH (-2080 205);
DISPLAY INVISIBLE (-2080 205);
FORCEPROP 1 LAST OFFPAGE TRUE
J 2
(-2450 175);
DISPLAY 0.872340 (-2450 175);
PAINT GREEN (-2450 175);
DISPLAY INVISIBLE (-2450 175);
FORCEPROP 2 LAST CDS_LIB standard
J 0
(-2125 300);
DISPLAY INVISIBLE (-2125 300);
FORCEADD OFFPAGE..3
R 2
(-2125 250);
FORCEPROP 2 LAST $XR1 28 
J 0
(-2464 250);
DISPLAY 0.638298 (-2464 250);
PAINT MONO (-2464 250);
FORCEPROP 2 LAST $XR0 27 
J 0
(-2374 250);
DISPLAY 0.638298 (-2374 250);
PAINT MONO (-2374 250);
FORCEPROP 2 LAST PATH I247
J 0
(-2075 325);
DISPLAY 1.021277 (-2075 325);
DISPLAY INVISIBLE (-2075 325);
FORCEPROP 1 LAST COMMENT_BODY TRUE
J 2
(-2075 150);
DISPLAY 0.872340 (-2075 150);
PAINT PEACH (-2075 150);
DISPLAY INVISIBLE (-2075 150);
FORCEPROP 1 LAST OFFPAGE TRUE
J 2
(-2450 125);
DISPLAY 0.872340 (-2450 125);
PAINT GREEN (-2450 125);
DISPLAY INVISIBLE (-2450 125);
FORCEPROP 2 LAST CDS_LIB standard
J 0
(-2125 250);
DISPLAY INVISIBLE (-2125 250);
FORCEADD Q_RES..1
(-650 150);
FORCEPROP 1 LAST VALUE 33.2
J 0
(-525 150);
DISPLAY 0.510638 (-525 150);
PAINT SKYBLUE (-525 150);
FORCEPROP 1 LAST MATERIAL CHIP
J 2
(-275 150);
DISPLAY 0.510638 (-275 150);
PAINT SKYBLUE (-275 150);
FORCEPROP 2 LAST CDS_LIB pure_quanta
J 0
(-650 150);
DISPLAY INVISIBLE (-650 150);
FORCEPROP 1 LAST PATH I248
J 0
(-700 300);
DISPLAY 0.978723 (-700 300);
PAINT WHITE (-700 300);
DISPLAY INVISIBLE (-700 300);
FORCEPROP 1 LAST TOLERANCE 1%
J 0
(-525 150);
DISPLAY 0.510638 (-525 150);
PAINT SKYBLUE (-525 150);
DISPLAY INVISIBLE (-525 150);
FORCEPROP 1 LAST PART_NUMBER CS03322FB03
J 0
(-700 250);
DISPLAY 0.510638 (-700 250);
PAINT WHITE (-700 250);
DISPLAY INVISIBLE (-700 250);
FORCEPROP 1 LAST WATTAGE 1/16W
J 2
(-675 0);
DISPLAY 0.510638 (-675 0);
PAINT SKYBLUE (-675 0);
DISPLAY INVISIBLE (-675 0);
FORCEPROP 1 LAST PACK_TYPE 0402LF
J 0
(-400 0);
DISPLAY 0.510638 (-400 0);
PAINT SKYBLUE (-400 0);
DISPLAY INVISIBLE (-400 0);
FORCEPROP 1 LAST LOCATION R153
J 2
(-825 150);
DISPLAY 0.702128 (-825 150);
PAINT YELLOW (-825 150);
FORCEPROP 1 LASTPIN (-750 150) $PN 1
J 0
(-735 160);
DISPLAY 0.808511 (-735 160);
PAINT WHITE (-735 160);
FORCEPROP 1 LASTPIN (-550 150) $PN 2
J 0
(-588 162);
DISPLAY 0.808511 (-588 162);
PAINT WHITE (-588 162);
FORCEPROP 0 LAST $SEC 1
J 0
(-550 200);
DISPLAY 0.680851 (-550 200);
PAINT MONO (-550 200);
DISPLAY INVISIBLE (-550 200);
FORCEPROP 0 LAST CDS_SEC 1
J 0
(-550 200);
DISPLAY 0.680851 (-550 200);
DISPLAY INVISIBLE (-550 200);
FORCEADD Q_RES..1
(-650 200);
FORCEPROP 1 LAST VALUE 33.2
J 0
(-525 200);
DISPLAY 0.510638 (-525 200);
PAINT SKYBLUE (-525 200);
FORCEPROP 1 LAST MATERIAL CHIP
J 2
(-275 200);
DISPLAY 0.510638 (-275 200);
PAINT SKYBLUE (-275 200);
FORCEPROP 2 LAST CDS_LIB pure_quanta
J 0
(-650 200);
DISPLAY INVISIBLE (-650 200);
FORCEPROP 1 LAST PATH I249
J 0
(-700 350);
DISPLAY 0.978723 (-700 350);
PAINT WHITE (-700 350);
DISPLAY INVISIBLE (-700 350);
FORCEPROP 1 LAST TOLERANCE 1%
J 0
(-525 200);
DISPLAY 0.510638 (-525 200);
PAINT SKYBLUE (-525 200);
DISPLAY INVISIBLE (-525 200);
FORCEPROP 1 LAST PART_NUMBER CS03322FB03
J 0
(-700 300);
DISPLAY 0.510638 (-700 300);
PAINT WHITE (-700 300);
DISPLAY INVISIBLE (-700 300);
FORCEPROP 1 LAST WATTAGE 1/16W
J 2
(-675 50);
DISPLAY 0.510638 (-675 50);
PAINT SKYBLUE (-675 50);
DISPLAY INVISIBLE (-675 50);
FORCEPROP 1 LAST PACK_TYPE 0402LF
J 0
(-400 50);
DISPLAY 0.510638 (-400 50);
PAINT SKYBLUE (-400 50);
DISPLAY INVISIBLE (-400 50);
FORCEPROP 1 LAST LOCATION R152
J 2
(-825 200);
DISPLAY 0.702128 (-825 200);
PAINT YELLOW (-825 200);
FORCEPROP 0 LAST $SEC 1
J 0
(-900 250);
DISPLAY 0.680851 (-900 250);
PAINT MONO (-900 250);
DISPLAY INVISIBLE (-900 250);
FORCEPROP 0 LAST CDS_SEC 1
J 0
(-900 250);
DISPLAY 1.021277 (-900 250);
DISPLAY INVISIBLE (-900 250);
FORCEPROP 1 LASTPIN (-750 200) $PN 1
J 0
(-738 212);
DISPLAY 0.808511 (-738 212);
PAINT WHITE (-738 212);
DISPLAY INVISIBLE (-738 212);
FORCEPROP 1 LASTPIN (-550 200) $PN 2
J 0
(-588 212);
DISPLAY 0.808511 (-588 212);
PAINT WHITE (-588 212);
DISPLAY INVISIBLE (-588 212);
FORCEADD UNIVERSAL_POWER..1
(-2200 3000);
FORCEPROP 3 LASTPIN (-2200 2950) SIG_NAME P0V6_DDR_VREF_AUX\g
J 0
(-2190 2960);
DISPLAY 0.659574 (-2190 2960);
PAINT MONO (-2190 2960);
DISPLAY INVISIBLE (-2190 2960);
FORCEPROP 1 LAST HDL_POWER P0V6_DDR_VREF_AUX
J 1
(-2200 3050);
DISPLAY 0.702128 (-2200 3050);
PAINT GREEN (-2200 3050);
FORCEPROP 1 LAST PATH I25
J 0
(-2150 3025);
DISPLAY 0.872340 (-2150 3025);
PAINT AQUA (-2150 3025);
DISPLAY INVISIBLE (-2150 3025);
FORCEPROP 2 LAST CDS_LIB logical_power
J 0
(-2200 3000);
DISPLAY INVISIBLE (-2200 3000);
FORCEADD OFFPAGE..3
R 2
(-2125 150);
FORCEPROP 2 LAST $XR1 27 
J 0
(-2464 150);
DISPLAY 0.638298 (-2464 150);
PAINT MONO (-2464 150);
FORCEPROP 2 LAST $XR0 26 
J 0
(-2374 150);
DISPLAY 0.638298 (-2374 150);
PAINT MONO (-2374 150);
FORCEPROP 2 LAST CDS_LIB standard
J 0
(-2125 150);
DISPLAY INVISIBLE (-2125 150);
FORCEPROP 1 LAST OFFPAGE TRUE
J 2
(-2450 25);
DISPLAY 0.872340 (-2450 25);
PAINT GREEN (-2450 25);
DISPLAY INVISIBLE (-2450 25);
FORCEPROP 1 LAST COMMENT_BODY TRUE
J 2
(-2075 50);
DISPLAY 0.872340 (-2075 50);
PAINT PEACH (-2075 50);
DISPLAY INVISIBLE (-2075 50);
FORCEPROP 2 LAST PATH I250
J 0
(-2075 225);
DISPLAY 1.021277 (-2075 225);
DISPLAY INVISIBLE (-2075 225);
FORCEADD OFFPAGE..2
R 2
(-2125 200);
FORCEPROP 2 LAST $XR1 26 
J 0
(-2469 200);
DISPLAY 0.638298 (-2469 200);
PAINT MONO (-2469 200);
FORCEPROP 2 LAST $XR0 27 
J 0
(-2379 200);
DISPLAY 0.638298 (-2379 200);
PAINT MONO (-2379 200);
FORCEPROP 2 LAST CDS_LIB standard
J 0
(-2125 200);
DISPLAY INVISIBLE (-2125 200);
FORCEPROP 1 LAST OFFPAGE TRUE
J 2
(-2450 75);
DISPLAY 0.872340 (-2450 75);
PAINT GREEN (-2450 75);
DISPLAY INVISIBLE (-2450 75);
FORCEPROP 1 LAST COMMENT_BODY TRUE
J 2
(-2080 105);
DISPLAY 0.872340 (-2080 105);
PAINT PEACH (-2080 105);
DISPLAY INVISIBLE (-2080 105);
FORCEPROP 2 LAST PATH I251
J 0
(-2075 275);
DISPLAY 1.021277 (-2075 275);
DISPLAY INVISIBLE (-2075 275);
FORCEADD Q_RES..1
(4375 250);
FORCEPROP 1 LAST MATERIAL CHIP
J 2
(4750 250);
DISPLAY 0.510638 (4750 250);
PAINT SKYBLUE (4750 250);
FORCEPROP 1 LAST VALUE 33.2
J 0
(4500 250);
DISPLAY 0.510638 (4500 250);
PAINT SKYBLUE (4500 250);
FORCEPROP 1 LAST PACK_TYPE 0402LF
J 0
(4625 100);
DISPLAY 0.510638 (4625 100);
PAINT SKYBLUE (4625 100);
DISPLAY INVISIBLE (4625 100);
FORCEPROP 1 LAST WATTAGE 1/16W
J 2
(4350 100);
DISPLAY 0.510638 (4350 100);
PAINT SKYBLUE (4350 100);
DISPLAY INVISIBLE (4350 100);
FORCEPROP 1 LAST PATH I252
J 0
(4325 400);
DISPLAY 0.978723 (4325 400);
PAINT WHITE (4325 400);
DISPLAY INVISIBLE (4325 400);
FORCEPROP 2 LAST CDS_LIB pure_quanta
J 0
(4375 250);
DISPLAY INVISIBLE (4375 250);
FORCEPROP 1 LAST PART_NUMBER CS03322FB03
J 0
(4325 350);
DISPLAY 0.510638 (4325 350);
PAINT WHITE (4325 350);
DISPLAY INVISIBLE (4325 350);
FORCEPROP 1 LAST TOLERANCE 1%
J 0
(4500 250);
DISPLAY 0.510638 (4500 250);
PAINT SKYBLUE (4500 250);
DISPLAY INVISIBLE (4500 250);
FORCEPROP 1 LAST LOCATION R423
J 2
(4200 250);
DISPLAY 0.702128 (4200 250);
PAINT YELLOW (4200 250);
FORCEPROP 0 LAST $SEC 1
J 0
(4125 300);
DISPLAY 0.680851 (4125 300);
PAINT MONO (4125 300);
DISPLAY INVISIBLE (4125 300);
FORCEPROP 0 LAST CDS_SEC 1
J 0
(4125 300);
DISPLAY 1.021277 (4125 300);
DISPLAY INVISIBLE (4125 300);
FORCEPROP 1 LASTPIN (4275 250) $PN 1
J 0
(4287 262);
DISPLAY 0.808511 (4287 262);
PAINT WHITE (4287 262);
DISPLAY INVISIBLE (4287 262);
FORCEPROP 1 LASTPIN (4475 250) $PN 2
J 0
(4437 262);
DISPLAY 0.808511 (4437 262);
PAINT WHITE (4437 262);
DISPLAY INVISIBLE (4437 262);
FORCEADD Q_RES..1
(4375 200);
FORCEPROP 1 LAST MATERIAL CHIP
J 2
(4750 200);
DISPLAY 0.510638 (4750 200);
PAINT SKYBLUE (4750 200);
FORCEPROP 1 LAST VALUE 33.2
J 0
(4500 200);
DISPLAY 0.510638 (4500 200);
PAINT SKYBLUE (4500 200);
FORCEPROP 1 LAST PACK_TYPE 0402LF
J 0
(4625 50);
DISPLAY 0.510638 (4625 50);
PAINT SKYBLUE (4625 50);
DISPLAY INVISIBLE (4625 50);
FORCEPROP 1 LAST WATTAGE 1/16W
J 2
(4350 50);
DISPLAY 0.510638 (4350 50);
PAINT SKYBLUE (4350 50);
DISPLAY INVISIBLE (4350 50);
FORCEPROP 1 LAST PATH I253
J 0
(4325 350);
DISPLAY 0.978723 (4325 350);
PAINT WHITE (4325 350);
DISPLAY INVISIBLE (4325 350);
FORCEPROP 2 LAST CDS_LIB pure_quanta
J 0
(4375 200);
DISPLAY INVISIBLE (4375 200);
FORCEPROP 1 LAST PART_NUMBER CS03322FB03
J 0
(4325 300);
DISPLAY 0.510638 (4325 300);
PAINT WHITE (4325 300);
DISPLAY INVISIBLE (4325 300);
FORCEPROP 1 LAST TOLERANCE 1%
J 0
(4500 200);
DISPLAY 0.510638 (4500 200);
PAINT SKYBLUE (4500 200);
DISPLAY INVISIBLE (4500 200);
FORCEPROP 1 LAST LOCATION R424
J 2
(4200 200);
DISPLAY 0.702128 (4200 200);
PAINT YELLOW (4200 200);
FORCEPROP 1 LASTPIN (4275 200) $PN 1
J 0
(4287 212);
DISPLAY 0.808511 (4287 212);
PAINT WHITE (4287 212);
FORCEPROP 1 LASTPIN (4475 200) $PN 2
J 0
(4437 212);
DISPLAY 0.808511 (4437 212);
PAINT WHITE (4437 212);
FORCEPROP 0 LAST $SEC 1
J 0
(4475 250);
DISPLAY 0.680851 (4475 250);
PAINT MONO (4475 250);
DISPLAY INVISIBLE (4475 250);
FORCEPROP 0 LAST CDS_SEC 1
J 0
(4475 250);
DISPLAY 0.680851 (4475 250);
DISPLAY INVISIBLE (4475 250);
FORCEADD Q_RES..1
(4375 150);
FORCEPROP 1 LAST MATERIAL CHIP
J 2
(4750 150);
DISPLAY 0.510638 (4750 150);
PAINT SKYBLUE (4750 150);
FORCEPROP 1 LAST VALUE 33.2
J 0
(4500 150);
DISPLAY 0.510638 (4500 150);
PAINT SKYBLUE (4500 150);
FORCEPROP 1 LAST PACK_TYPE 0402LF
J 0
(4625 0);
DISPLAY 0.510638 (4625 0);
PAINT SKYBLUE (4625 0);
DISPLAY INVISIBLE (4625 0);
FORCEPROP 1 LAST WATTAGE 1/16W
J 2
(4350 0);
DISPLAY 0.510638 (4350 0);
PAINT SKYBLUE (4350 0);
DISPLAY INVISIBLE (4350 0);
FORCEPROP 1 LAST PATH I254
J 0
(4325 300);
DISPLAY 0.978723 (4325 300);
PAINT WHITE (4325 300);
DISPLAY INVISIBLE (4325 300);
FORCEPROP 2 LAST CDS_LIB pure_quanta
J 0
(4375 150);
DISPLAY INVISIBLE (4375 150);
FORCEPROP 1 LAST PART_NUMBER CS03322FB03
J 0
(4325 250);
DISPLAY 0.510638 (4325 250);
PAINT WHITE (4325 250);
DISPLAY INVISIBLE (4325 250);
FORCEPROP 1 LAST TOLERANCE 1%
J 0
(4500 150);
DISPLAY 0.510638 (4500 150);
PAINT SKYBLUE (4500 150);
DISPLAY INVISIBLE (4500 150);
FORCEPROP 1 LAST LOCATION R425
J 2
(4200 150);
DISPLAY 0.702128 (4200 150);
PAINT YELLOW (4200 150);
FORCEPROP 0 LAST $SEC 1
J 0
(4125 200);
DISPLAY 0.680851 (4125 200);
PAINT MONO (4125 200);
DISPLAY INVISIBLE (4125 200);
FORCEPROP 0 LAST CDS_SEC 1
J 0
(4125 200);
DISPLAY 1.021277 (4125 200);
DISPLAY INVISIBLE (4125 200);
FORCEPROP 1 LASTPIN (4275 150) $PN 1
J 0
(4287 162);
DISPLAY 0.808511 (4287 162);
PAINT WHITE (4287 162);
DISPLAY INVISIBLE (4287 162);
FORCEPROP 1 LASTPIN (4475 150) $PN 2
J 0
(4437 162);
DISPLAY 0.808511 (4437 162);
PAINT WHITE (4437 162);
DISPLAY INVISIBLE (4437 162);
FORCEADD Q_RES..1
(4375 100);
FORCEPROP 1 LAST MATERIAL CHIP
J 2
(4750 100);
DISPLAY 0.510638 (4750 100);
PAINT SKYBLUE (4750 100);
FORCEPROP 1 LAST VALUE 33.2
J 0
(4500 100);
DISPLAY 0.510638 (4500 100);
PAINT SKYBLUE (4500 100);
FORCEPROP 1 LAST PACK_TYPE 0402LF
J 0
(4625 -50);
DISPLAY 0.510638 (4625 -50);
PAINT SKYBLUE (4625 -50);
DISPLAY INVISIBLE (4625 -50);
FORCEPROP 1 LAST WATTAGE 1/16W
J 2
(4350 -50);
DISPLAY 0.510638 (4350 -50);
PAINT SKYBLUE (4350 -50);
DISPLAY INVISIBLE (4350 -50);
FORCEPROP 1 LAST PATH I255
J 0
(4325 250);
DISPLAY 0.978723 (4325 250);
PAINT WHITE (4325 250);
DISPLAY INVISIBLE (4325 250);
FORCEPROP 2 LAST CDS_LIB pure_quanta
J 0
(4375 100);
DISPLAY INVISIBLE (4375 100);
FORCEPROP 1 LAST PART_NUMBER CS03322FB03
J 0
(4325 200);
DISPLAY 0.510638 (4325 200);
PAINT WHITE (4325 200);
DISPLAY INVISIBLE (4325 200);
FORCEPROP 1 LAST TOLERANCE 1%
J 0
(4500 100);
DISPLAY 0.510638 (4500 100);
PAINT SKYBLUE (4500 100);
DISPLAY INVISIBLE (4500 100);
FORCEPROP 1 LAST LOCATION R426
J 2
(4200 100);
DISPLAY 0.702128 (4200 100);
PAINT YELLOW (4200 100);
FORCEPROP 1 LASTPIN (4275 100) $PN 1
J 0
(4287 112);
DISPLAY 0.808511 (4287 112);
PAINT WHITE (4287 112);
FORCEPROP 1 LASTPIN (4475 100) $PN 2
J 0
(4437 112);
DISPLAY 0.808511 (4437 112);
PAINT WHITE (4437 112);
FORCEPROP 0 LAST $SEC 1
J 0
(4475 150);
DISPLAY 0.680851 (4475 150);
PAINT MONO (4475 150);
DISPLAY INVISIBLE (4475 150);
FORCEPROP 0 LAST CDS_SEC 1
J 0
(4475 150);
DISPLAY 0.680851 (4475 150);
DISPLAY INVISIBLE (4475 150);
FORCEADD UNIVERSAL_GND..1
(-1700 2200);
FORCEPROP 3 LASTPIN (-1700 2250) SIG_NAME GND\g
J 0
(-1690 2260);
DISPLAY 0.659574 (-1690 2260);
PAINT MONO (-1690 2260);
DISPLAY INVISIBLE (-1690 2260);
FORCEPROP 1 LAST PATH I26
J 0
(-1625 2200);
DISPLAY 0.872340 (-1625 2200);
PAINT AQUA (-1625 2200);
DISPLAY INVISIBLE (-1625 2200);
FORCEPROP 1 LAST HDL_POWER GND
J 1
(-1675 2125);
DISPLAY 0.702128 (-1675 2125);
PAINT GREEN (-1675 2125);
DISPLAY INVISIBLE (-1675 2125);
FORCEPROP 2 LAST CDS_LIB logical_power
R 1
J 0
(-1700 2200);
DISPLAY INVISIBLE (-1700 2200);
FORCEADD OFFPAGE..2
(5875 250);
FORCEPROP 2 LAST $XR1 10 
J 0
(6154 250);
DISPLAY 0.638298 (6154 250);
PAINT MONO (6154 250);
FORCEPROP 2 LAST $XR0 27 
J 0
(6064 250);
DISPLAY 0.638298 (6064 250);
PAINT MONO (6064 250);
FORCEPROP 2 LAST PATH I260
J 0
(6050 325);
DISPLAY 1.021277 (6050 325);
DISPLAY INVISIBLE (6050 325);
FORCEPROP 1 LAST COMMENT_BODY TRUE
J 0
(5830 155);
DISPLAY 0.872340 (5830 155);
PAINT PEACH (5830 155);
DISPLAY INVISIBLE (5830 155);
FORCEPROP 1 LAST OFFPAGE TRUE
J 0
(6200 125);
DISPLAY 0.872340 (6200 125);
PAINT GREEN (6200 125);
DISPLAY INVISIBLE (6200 125);
FORCEPROP 2 LAST CDS_LIB standard
J 0
(5875 250);
DISPLAY INVISIBLE (5875 250);
FORCEADD OFFPAGE..2
(5875 200);
FORCEPROP 2 LAST $XR1 27 
J 0
(6154 200);
DISPLAY 0.638298 (6154 200);
PAINT MONO (6154 200);
FORCEPROP 2 LAST $XR0 10 
J 0
(6064 200);
DISPLAY 0.638298 (6064 200);
PAINT MONO (6064 200);
FORCEPROP 2 LAST PATH I261
J 0
(6050 275);
DISPLAY 1.021277 (6050 275);
DISPLAY INVISIBLE (6050 275);
FORCEPROP 1 LAST COMMENT_BODY TRUE
J 0
(5830 105);
DISPLAY 0.872340 (5830 105);
PAINT PEACH (5830 105);
DISPLAY INVISIBLE (5830 105);
FORCEPROP 1 LAST OFFPAGE TRUE
J 0
(6200 75);
DISPLAY 0.872340 (6200 75);
PAINT GREEN (6200 75);
DISPLAY INVISIBLE (6200 75);
FORCEPROP 2 LAST CDS_LIB standard
J 0
(5875 200);
DISPLAY INVISIBLE (5875 200);
FORCEADD OFFPAGE..2
(5875 150);
FORCEPROP 2 LAST $XR1 10 
J 0
(6154 150);
DISPLAY 0.638298 (6154 150);
PAINT MONO (6154 150);
FORCEPROP 2 LAST $XR0 27 
J 0
(6064 150);
DISPLAY 0.638298 (6064 150);
PAINT MONO (6064 150);
FORCEPROP 2 LAST PATH I262
J 0
(6050 225);
DISPLAY 1.021277 (6050 225);
DISPLAY INVISIBLE (6050 225);
FORCEPROP 1 LAST COMMENT_BODY TRUE
J 0
(5830 55);
DISPLAY 0.872340 (5830 55);
PAINT PEACH (5830 55);
DISPLAY INVISIBLE (5830 55);
FORCEPROP 1 LAST OFFPAGE TRUE
J 0
(6200 25);
DISPLAY 0.872340 (6200 25);
PAINT GREEN (6200 25);
DISPLAY INVISIBLE (6200 25);
FORCEPROP 2 LAST CDS_LIB standard
J 0
(5875 150);
DISPLAY INVISIBLE (5875 150);
FORCEADD OFFPAGE..2
(125 -1150);
FORCEPROP 2 LAST $XR0 13 
J 0
(314 -1150);
DISPLAY 0.638298 (314 -1150);
PAINT MONO (314 -1150);
FORCEPROP 2 LAST PATH I267
J 0
(325 -1100);
DISPLAY 1.021277 (325 -1100);
DISPLAY INVISIBLE (325 -1100);
FORCEPROP 1 LAST COMMENT_BODY TRUE
J 0
(80 -1245);
DISPLAY 0.872340 (80 -1245);
PAINT PEACH (80 -1245);
DISPLAY INVISIBLE (80 -1245);
FORCEPROP 1 LAST OFFPAGE TRUE
J 0
(450 -1275);
DISPLAY 0.872340 (450 -1275);
PAINT GREEN (450 -1275);
DISPLAY INVISIBLE (450 -1275);
FORCEPROP 2 LAST CDS_LIB standard
J 0
(125 -1150);
DISPLAY INVISIBLE (125 -1150);
FORCEADD Q_RES..1
(-775 -1150);
FORCEPROP 1 LAST VALUE 33.2
J 2
(-875 -1150);
DISPLAY 0.510638 (-875 -1150);
PAINT SKYBLUE (-875 -1150);
FORCEPROP 1 LAST MATERIAL CHIP
J 0
(-650 -1150);
DISPLAY 0.510638 (-650 -1150);
PAINT SKYBLUE (-650 -1150);
FORCEPROP 1 LAST PACK_TYPE 0402LF
J 0
(-775 -1250);
DISPLAY 0.510638 (-775 -1250);
PAINT SKYBLUE (-775 -1250);
DISPLAY INVISIBLE (-775 -1250);
FORCEPROP 1 LAST WATTAGE 1/16W
J 2
(-650 -1225);
DISPLAY 0.510638 (-650 -1225);
PAINT SKYBLUE (-650 -1225);
DISPLAY INVISIBLE (-650 -1225);
FORCEPROP 1 LAST PATH I268
J 0
(-825 -1000);
DISPLAY 0.978723 (-825 -1000);
PAINT WHITE (-825 -1000);
DISPLAY INVISIBLE (-825 -1000);
FORCEPROP 2 LAST CDS_LIB pure_quanta
J 0
(-775 -1150);
DISPLAY INVISIBLE (-775 -1150);
FORCEPROP 1 LAST PART_NUMBER CS03322FB03
J 0
(-850 -1275);
DISPLAY 0.510638 (-850 -1275);
PAINT WHITE (-850 -1275);
DISPLAY INVISIBLE (-850 -1275);
FORCEPROP 1 LAST TOLERANCE 1%
J 0
(-750 -1200);
DISPLAY 0.510638 (-750 -1200);
PAINT SKYBLUE (-750 -1200);
DISPLAY INVISIBLE (-750 -1200);
FORCEPROP 1 LAST LOCATION R168
J 0
(-1075 -1150);
DISPLAY 0.702128 (-1075 -1150);
PAINT YELLOW (-1075 -1150);
FORCEPROP 1 LASTPIN (-875 -1150) $PN 1
J 0
(-863 -1138);
DISPLAY 0.808511 (-863 -1138);
PAINT WHITE (-863 -1138);
FORCEPROP 1 LASTPIN (-675 -1150) $PN 2
J 0
(-713 -1138);
DISPLAY 0.808511 (-713 -1138);
PAINT WHITE (-713 -1138);
FORCEPROP 2 LAST $SEC 1
J 0
(-825 -950);
DISPLAY 0.680851 (-825 -950);
PAINT MONO (-825 -950);
DISPLAY INVISIBLE (-825 -950);
FORCEPROP 2 LAST CDS_SEC 1
J 0
(-825 -950);
DISPLAY 0.680851 (-825 -950);
DISPLAY INVISIBLE (-825 -950);
FORCEADD OFFPAGE..1
(-1775 -1150);
FORCEPROP 2 LAST $XR5 46 
J 0
(-2446 -1150);
DISPLAY 0.638298 (-2446 -1150);
PAINT MONO (-2446 -1150);
FORCEPROP 2 LAST $XR4 34 
J 0
(-2356 -1150);
DISPLAY 0.638298 (-2356 -1150);
PAINT MONO (-2356 -1150);
FORCEPROP 2 LAST $XR3 28 
J 0
(-2266 -1150);
DISPLAY 0.638298 (-2266 -1150);
PAINT MONO (-2266 -1150);
FORCEPROP 2 LAST $XR2 12 
J 0
(-2176 -1150);
DISPLAY 0.638298 (-2176 -1150);
PAINT MONO (-2176 -1150);
FORCEPROP 2 LAST $XR1 11 
J 0
(-2086 -1150);
DISPLAY 0.638298 (-2086 -1150);
PAINT MONO (-2086 -1150);
FORCEPROP 2 LAST $XR0 10 
J 0
(-1996 -1150);
DISPLAY 0.638298 (-1996 -1150);
PAINT MONO (-1996 -1150);
FORCEPROP 2 LAST PATH I269
J 0
(-1950 -1100);
DISPLAY 1.021277 (-1950 -1100);
DISPLAY INVISIBLE (-1950 -1100);
FORCEPROP 1 LAST COMMENT_BODY TRUE
J 0
(-1650 -1250);
DISPLAY 0.872340 (-1650 -1250);
PAINT PEACH (-1650 -1250);
DISPLAY INVISIBLE (-1650 -1250);
FORCEPROP 1 LAST OFFPAGE TRUE
J 0
(-1450 -1275);
DISPLAY 0.872340 (-1450 -1275);
PAINT GREEN (-1450 -1275);
DISPLAY INVISIBLE (-1450 -1275);
FORCEPROP 2 LAST CDS_LIB standard
J 0
(-1775 -1150);
DISPLAY INVISIBLE (-1775 -1150);
FORCEADD OFFPAGE..3
(5875 -500);
FORCEPROP 2 LAST $XR0 10 
J 0
(6089 -500);
DISPLAY 0.638298 (6089 -500);
PAINT MONO (6089 -500);
FORCEPROP 2 LAST CDS_LIB standard
J 0
(5875 -500);
DISPLAY INVISIBLE (5875 -500);
FORCEPROP 1 LAST OFFPAGE TRUE
J 0
(6200 -625);
DISPLAY 0.872340 (6200 -625);
PAINT GREEN (6200 -625);
DISPLAY INVISIBLE (6200 -625);
FORCEPROP 1 LAST COMMENT_BODY TRUE
J 0
(5825 -600);
DISPLAY 0.872340 (5825 -600);
PAINT PEACH (5825 -600);
DISPLAY INVISIBLE (5825 -600);
FORCEPROP 2 LAST PATH I271
J 0
(6250 -450);
DISPLAY 1.021277 (6250 -450);
DISPLAY INVISIBLE (6250 -450);
FORCEADD OFFPAGE..3
(5875 -400);
FORCEPROP 2 LAST $XR0 10 
J 0
(6089 -400);
DISPLAY 0.638298 (6089 -400);
PAINT MONO (6089 -400);
FORCEPROP 2 LAST CDS_LIB standard
J 0
(5875 -400);
DISPLAY INVISIBLE (5875 -400);
FORCEPROP 1 LAST OFFPAGE TRUE
J 0
(6200 -525);
DISPLAY 0.872340 (6200 -525);
PAINT GREEN (6200 -525);
DISPLAY INVISIBLE (6200 -525);
FORCEPROP 1 LAST COMMENT_BODY TRUE
J 0
(5825 -500);
DISPLAY 0.872340 (5825 -500);
PAINT PEACH (5825 -500);
DISPLAY INVISIBLE (5825 -500);
FORCEPROP 2 LAST PATH I272
J 0
(6150 -350);
DISPLAY 1.021277 (6150 -350);
DISPLAY INVISIBLE (6150 -350);
FORCEADD Q_RES..1
(4775 -450);
FORCEPROP 1 LAST VALUE 33.2
J 0
(4900 -450);
DISPLAY 0.510638 (4900 -450);
PAINT SKYBLUE (4900 -450);
FORCEPROP 1 LAST MATERIAL CHIP
J 2
(5150 -450);
DISPLAY 0.510638 (5150 -450);
PAINT SKYBLUE (5150 -450);
FORCEPROP 1 LAST PACK_TYPE 0402LF
J 0
(5025 -600);
DISPLAY 0.510638 (5025 -600);
PAINT SKYBLUE (5025 -600);
DISPLAY INVISIBLE (5025 -600);
FORCEPROP 1 LAST WATTAGE 1/16W
J 2
(4750 -600);
DISPLAY 0.510638 (4750 -600);
PAINT SKYBLUE (4750 -600);
DISPLAY INVISIBLE (4750 -600);
FORCEPROP 1 LAST PATH I274
J 0
(4725 -300);
DISPLAY 0.978723 (4725 -300);
PAINT WHITE (4725 -300);
DISPLAY INVISIBLE (4725 -300);
FORCEPROP 2 LAST CDS_LIB pure_quanta
J 0
(4775 -450);
DISPLAY INVISIBLE (4775 -450);
FORCEPROP 1 LAST PART_NUMBER CS03322FB03
J 0
(4725 -350);
DISPLAY 0.510638 (4725 -350);
PAINT WHITE (4725 -350);
DISPLAY INVISIBLE (4725 -350);
FORCEPROP 1 LAST TOLERANCE 1%
J 0
(4900 -450);
DISPLAY 0.510638 (4900 -450);
PAINT SKYBLUE (4900 -450);
DISPLAY INVISIBLE (4900 -450);
FORCEPROP 1 LAST LOCATION R567
J 2
(4600 -450);
DISPLAY 0.702128 (4600 -450);
PAINT YELLOW (4600 -450);
FORCEPROP 0 LAST $SEC 1
J 0
(4525 -400);
DISPLAY 0.680851 (4525 -400);
PAINT MONO (4525 -400);
DISPLAY INVISIBLE (4525 -400);
FORCEPROP 0 LAST CDS_SEC 1
J 0
(4525 -400);
DISPLAY 1.021277 (4525 -400);
DISPLAY INVISIBLE (4525 -400);
FORCEPROP 1 LASTPIN (4675 -450) $PN 1
J 0
(4687 -438);
DISPLAY 0.808511 (4687 -438);
PAINT WHITE (4687 -438);
DISPLAY INVISIBLE (4687 -438);
FORCEPROP 1 LASTPIN (4875 -450) $PN 2
J 0
(4837 -438);
DISPLAY 0.808511 (4837 -438);
PAINT WHITE (4837 -438);
DISPLAY INVISIBLE (4837 -438);
FORCEADD Q_RES..1
(4775 -500);
FORCEPROP 1 LAST VALUE 33.2
J 0
(4900 -500);
DISPLAY 0.510638 (4900 -500);
PAINT SKYBLUE (4900 -500);
FORCEPROP 1 LAST MATERIAL CHIP
J 2
(5150 -500);
DISPLAY 0.510638 (5150 -500);
PAINT SKYBLUE (5150 -500);
FORCEPROP 1 LAST PACK_TYPE 0402LF
J 0
(5025 -650);
DISPLAY 0.510638 (5025 -650);
PAINT SKYBLUE (5025 -650);
DISPLAY INVISIBLE (5025 -650);
FORCEPROP 1 LAST WATTAGE 1/16W
J 2
(4750 -650);
DISPLAY 0.510638 (4750 -650);
PAINT SKYBLUE (4750 -650);
DISPLAY INVISIBLE (4750 -650);
FORCEPROP 1 LAST PATH I275
J 0
(4725 -350);
DISPLAY 0.978723 (4725 -350);
PAINT WHITE (4725 -350);
DISPLAY INVISIBLE (4725 -350);
FORCEPROP 2 LAST CDS_LIB pure_quanta
J 0
(4775 -500);
DISPLAY INVISIBLE (4775 -500);
FORCEPROP 1 LAST PART_NUMBER CS03322FB03
J 0
(4725 -400);
DISPLAY 0.510638 (4725 -400);
PAINT WHITE (4725 -400);
DISPLAY INVISIBLE (4725 -400);
FORCEPROP 1 LAST TOLERANCE 1%
J 0
(4900 -500);
DISPLAY 0.510638 (4900 -500);
PAINT SKYBLUE (4900 -500);
DISPLAY INVISIBLE (4900 -500);
FORCEPROP 1 LAST LOCATION R570
J 2
(4600 -500);
DISPLAY 0.702128 (4600 -500);
PAINT YELLOW (4600 -500);
FORCEPROP 1 LASTPIN (4675 -500) $PN 1
J 0
(4687 -488);
DISPLAY 0.808511 (4687 -488);
PAINT WHITE (4687 -488);
FORCEPROP 1 LASTPIN (4875 -500) $PN 2
J 0
(4837 -488);
DISPLAY 0.808511 (4837 -488);
PAINT WHITE (4837 -488);
FORCEPROP 0 LAST $SEC 1
J 0
(4875 -450);
DISPLAY 0.680851 (4875 -450);
PAINT MONO (4875 -450);
DISPLAY INVISIBLE (4875 -450);
FORCEPROP 0 LAST CDS_SEC 1
J 0
(4875 -450);
DISPLAY 0.680851 (4875 -450);
DISPLAY INVISIBLE (4875 -450);
FORCEADD Q_RES..1
(4775 -400);
FORCEPROP 1 LAST VALUE 33.2
J 0
(4900 -400);
DISPLAY 0.510638 (4900 -400);
PAINT SKYBLUE (4900 -400);
FORCEPROP 1 LAST MATERIAL CHIP
J 2
(5150 -400);
DISPLAY 0.510638 (5150 -400);
PAINT SKYBLUE (5150 -400);
FORCEPROP 1 LAST PACK_TYPE 0402LF
J 0
(5025 -550);
DISPLAY 0.510638 (5025 -550);
PAINT SKYBLUE (5025 -550);
DISPLAY INVISIBLE (5025 -550);
FORCEPROP 1 LAST WATTAGE 1/16W
J 2
(4750 -550);
DISPLAY 0.510638 (4750 -550);
PAINT SKYBLUE (4750 -550);
DISPLAY INVISIBLE (4750 -550);
FORCEPROP 1 LAST PATH I276
J 0
(4725 -250);
DISPLAY 0.978723 (4725 -250);
PAINT WHITE (4725 -250);
DISPLAY INVISIBLE (4725 -250);
FORCEPROP 2 LAST CDS_LIB pure_quanta
J 0
(4775 -400);
DISPLAY INVISIBLE (4775 -400);
FORCEPROP 1 LAST PART_NUMBER CS03322FB03
J 0
(4725 -300);
DISPLAY 0.510638 (4725 -300);
PAINT WHITE (4725 -300);
DISPLAY INVISIBLE (4725 -300);
FORCEPROP 1 LAST TOLERANCE 1%
J 0
(4900 -400);
DISPLAY 0.510638 (4900 -400);
PAINT SKYBLUE (4900 -400);
DISPLAY INVISIBLE (4900 -400);
FORCEPROP 1 LAST LOCATION R93
J 2
(4600 -400);
DISPLAY 0.702128 (4600 -400);
PAINT YELLOW (4600 -400);
FORCEPROP 1 LASTPIN (4675 -400) $PN 1
J 0
(4687 -388);
DISPLAY 0.808511 (4687 -388);
PAINT WHITE (4687 -388);
FORCEPROP 1 LASTPIN (4875 -400) $PN 2
J 0
(4837 -388);
DISPLAY 0.808511 (4837 -388);
PAINT WHITE (4837 -388);
FORCEPROP 0 LAST $SEC 1
J 0
(4875 -350);
DISPLAY 0.680851 (4875 -350);
PAINT MONO (4875 -350);
DISPLAY INVISIBLE (4875 -350);
FORCEPROP 0 LAST CDS_SEC 1
J 0
(4875 -350);
DISPLAY 0.680851 (4875 -350);
DISPLAY INVISIBLE (4875 -350);
FORCEADD Q_RES..1
(4775 -350);
FORCEPROP 1 LAST VALUE 33.2
J 0
(4900 -350);
DISPLAY 0.510638 (4900 -350);
PAINT SKYBLUE (4900 -350);
FORCEPROP 1 LAST MATERIAL CHIP
J 2
(5150 -350);
DISPLAY 0.510638 (5150 -350);
PAINT SKYBLUE (5150 -350);
FORCEPROP 1 LAST PACK_TYPE 0402LF
J 0
(5025 -500);
DISPLAY 0.510638 (5025 -500);
PAINT SKYBLUE (5025 -500);
DISPLAY INVISIBLE (5025 -500);
FORCEPROP 1 LAST WATTAGE 1/16W
J 2
(4750 -500);
DISPLAY 0.510638 (4750 -500);
PAINT SKYBLUE (4750 -500);
DISPLAY INVISIBLE (4750 -500);
FORCEPROP 1 LAST PATH I277
J 0
(4725 -200);
DISPLAY 0.978723 (4725 -200);
PAINT WHITE (4725 -200);
DISPLAY INVISIBLE (4725 -200);
FORCEPROP 2 LAST CDS_LIB pure_quanta
J 0
(4775 -350);
DISPLAY INVISIBLE (4775 -350);
FORCEPROP 1 LAST PART_NUMBER CS03322FB03
J 0
(4725 -250);
DISPLAY 0.510638 (4725 -250);
PAINT WHITE (4725 -250);
DISPLAY INVISIBLE (4725 -250);
FORCEPROP 1 LAST TOLERANCE 1%
J 0
(4900 -350);
DISPLAY 0.510638 (4900 -350);
PAINT SKYBLUE (4900 -350);
DISPLAY INVISIBLE (4900 -350);
FORCEPROP 1 LAST LOCATION R71
J 2
(4600 -350);
DISPLAY 0.702128 (4600 -350);
PAINT YELLOW (4600 -350);
FORCEPROP 0 LAST $SEC 1
J 0
(4525 -300);
DISPLAY 0.680851 (4525 -300);
PAINT MONO (4525 -300);
DISPLAY INVISIBLE (4525 -300);
FORCEPROP 0 LAST CDS_SEC 1
J 0
(4600 -300);
DISPLAY 0.680851 (4600 -300);
DISPLAY INVISIBLE (4600 -300);
FORCEPROP 1 LASTPIN (4675 -350) $PN 1
J 0
(4687 -338);
DISPLAY 0.808511 (4687 -338);
PAINT WHITE (4687 -338);
DISPLAY INVISIBLE (4687 -338);
FORCEPROP 1 LASTPIN (4875 -350) $PN 2
J 0
(4837 -338);
DISPLAY 0.808511 (4837 -338);
PAINT WHITE (4837 -338);
DISPLAY INVISIBLE (4837 -338);
FORCEADD Q_CAP..1
(-1550 2625);
FORCEPROP 1 LAST PART_NUMBER CH4104K1B00
J 0
(-1500 2425);
DISPLAY 0.510638 (-1500 2425);
PAINT WHITE (-1500 2425);
FORCEPROP 1 LAST VALUE 0.1UF
J 0
(-1500 2675);
DISPLAY 0.510638 (-1500 2675);
PAINT SKYBLUE (-1500 2675);
FORCEPROP 1 LAST TOLERANCE 10%
J 0
(-1500 2575);
DISPLAY 0.510638 (-1500 2575);
PAINT SKYBLUE (-1500 2575);
FORCEPROP 1 LAST MATERIAL X7R
J 0
(-1500 2525);
DISPLAY 0.510638 (-1500 2525);
PAINT SKYBLUE (-1500 2525);
FORCEPROP 1 LAST VOLTAGE 25V
J 0
(-1500 2625);
DISPLAY 0.510638 (-1500 2625);
PAINT SKYBLUE (-1500 2625);
FORCEPROP 1 LAST PACK_TYPE 0402
J 0
(-1500 2475);
DISPLAY 0.510638 (-1500 2475);
PAINT SKYBLUE (-1500 2475);
FORCEPROP 1 LAST PATH I28
J 0
(-1500 2775);
DISPLAY 0.978723 (-1500 2775);
PAINT WHITE (-1500 2775);
DISPLAY INVISIBLE (-1500 2775);
FORCEPROP 2 LAST CDS_LIB pure_quanta
J 0
(-1550 2625);
DISPLAY INVISIBLE (-1550 2625);
FORCEPROP 1 LAST LOCATION C23
J 0
(-1500 2725);
DISPLAY 0.702128 (-1500 2725);
PAINT YELLOW (-1500 2725);
FORCEPROP 1 LASTPIN (-1550 2725) $PN 1
J 0
(-1540 2705);
DISPLAY 0.808511 (-1540 2705);
PAINT WHITE (-1540 2705);
FORCEPROP 1 LASTPIN (-1550 2525) $PN 2
J 0
(-1540 2505);
DISPLAY 0.808511 (-1540 2505);
PAINT WHITE (-1540 2505);
FORCEPROP 2 LAST $SEC 1
J 0
(-1500 2825);
DISPLAY 0.680851 (-1500 2825);
PAINT MONO (-1500 2825);
DISPLAY INVISIBLE (-1500 2825);
FORCEPROP 0 LAST CDS_SEC 1
J 0
(-1500 2825);
DISPLAY 0.680851 (-1500 2825);
PAINT MONO (-1500 2825);
DISPLAY INVISIBLE (-1500 2825);
FORCEADD OFFPAGE..5
(3575 -350);
FORCEPROP 2 LAST $XR1 27 
J 0
(3261 -350);
DISPLAY 0.638298 (3261 -350);
PAINT MONO (3261 -350);
FORCEPROP 2 LAST $XR0 12 
J 0
(3351 -350);
DISPLAY 0.638298 (3351 -350);
PAINT MONO (3351 -350);
FORCEPROP 2 LAST PATH I282
J 0
(3750 -275);
DISPLAY 1.021277 (3750 -275);
DISPLAY INVISIBLE (3750 -275);
FORCEPROP 1 LAST COMMENT_BODY TRUE
J 0
(3675 -425);
DISPLAY 0.872340 (3675 -425);
PAINT PEACH (3675 -425);
DISPLAY INVISIBLE (3675 -425);
FORCEPROP 1 LAST OFFPAGE TRUE
J 0
(3900 -475);
DISPLAY 0.872340 (3900 -475);
PAINT GREEN (3900 -475);
DISPLAY INVISIBLE (3900 -475);
FORCEPROP 2 LAST CDS_LIB standard
J 0
(3575 -350);
DISPLAY INVISIBLE (3575 -350);
FORCEADD OFFPAGE..6
(3575 -400);
FORCEPROP 2 LAST $XR1 27 
J 0
(3236 -400);
DISPLAY 0.638298 (3236 -400);
PAINT MONO (3236 -400);
FORCEPROP 2 LAST $XR0 12 
J 0
(3326 -400);
DISPLAY 0.638298 (3326 -400);
PAINT MONO (3326 -400);
FORCEPROP 2 LAST PATH I283
J 0
(3625 -325);
DISPLAY 1.021277 (3625 -325);
DISPLAY INVISIBLE (3625 -325);
FORCEPROP 1 LAST COMMENT_BODY TRUE
J 0
(3675 -475);
DISPLAY 0.872340 (3675 -475);
PAINT PEACH (3675 -475);
DISPLAY INVISIBLE (3675 -475);
FORCEPROP 1 LAST OFFPAGE TRUE
J 0
(3900 -525);
DISPLAY 0.872340 (3900 -525);
PAINT GREEN (3900 -525);
DISPLAY INVISIBLE (3900 -525);
FORCEPROP 2 LAST CDS_LIB standard
J 0
(3575 -400);
DISPLAY INVISIBLE (3575 -400);
FORCEADD OFFPAGE..5
(3575 -450);
FORCEPROP 2 LAST $XR0 12 
J 0
(3321 -450);
DISPLAY 0.638298 (3321 -450);
PAINT MONO (3321 -450);
FORCEPROP 2 LAST $XR1 27 
J 0
(3231 -450);
DISPLAY 0.638298 (3231 -450);
PAINT MONO (3231 -450);
FORCEPROP 2 LAST PATH I284
J 0
(3625 -375);
DISPLAY 1.021277 (3625 -375);
DISPLAY INVISIBLE (3625 -375);
FORCEPROP 1 LAST COMMENT_BODY TRUE
J 0
(3675 -525);
DISPLAY 0.872340 (3675 -525);
PAINT PEACH (3675 -525);
DISPLAY INVISIBLE (3675 -525);
FORCEPROP 1 LAST OFFPAGE TRUE
J 0
(3900 -575);
DISPLAY 0.872340 (3900 -575);
PAINT GREEN (3900 -575);
DISPLAY INVISIBLE (3900 -575);
FORCEPROP 2 LAST CDS_LIB standard
J 0
(3575 -450);
DISPLAY INVISIBLE (3575 -450);
FORCEADD OFFPAGE..6
(3575 -500);
FORCEPROP 2 LAST $XR1 27 
J 0
(3236 -500);
DISPLAY 0.638298 (3236 -500);
PAINT MONO (3236 -500);
FORCEPROP 2 LAST $XR0 12 
J 0
(3326 -500);
DISPLAY 0.638298 (3326 -500);
PAINT MONO (3326 -500);
FORCEPROP 2 LAST PATH I285
J 0
(3625 -425);
DISPLAY 1.021277 (3625 -425);
DISPLAY INVISIBLE (3625 -425);
FORCEPROP 1 LAST COMMENT_BODY TRUE
J 0
(3675 -575);
DISPLAY 0.872340 (3675 -575);
PAINT PEACH (3675 -575);
DISPLAY INVISIBLE (3675 -575);
FORCEPROP 1 LAST OFFPAGE TRUE
J 0
(3900 -625);
DISPLAY 0.872340 (3900 -625);
PAINT GREEN (3900 -625);
DISPLAY INVISIBLE (3900 -625);
FORCEPROP 2 LAST CDS_LIB standard
J 0
(3575 -500);
DISPLAY INVISIBLE (3575 -500);
FORCEADD Q_RES..1
(-1475 -375);
FORCEPROP 1 LAST MATERIAL CHIP
J 0
(-1350 -375);
DISPLAY 0.510638 (-1350 -375);
PAINT SKYBLUE (-1350 -375);
FORCEPROP 1 LAST VALUE 4.7K
J 2
(-1600 -375);
DISPLAY 0.510638 (-1600 -375);
PAINT SKYBLUE (-1600 -375);
FORCEPROP 1 LAST PACK_TYPE 0402LF
J 0
(-1225 -525);
DISPLAY 0.510638 (-1225 -525);
PAINT SKYBLUE (-1225 -525);
DISPLAY INVISIBLE (-1225 -525);
FORCEPROP 1 LAST WATTAGE 1/16W
J 2
(-1500 -525);
DISPLAY 0.510638 (-1500 -525);
PAINT SKYBLUE (-1500 -525);
DISPLAY INVISIBLE (-1500 -525);
FORCEPROP 1 LAST PATH I3
J 0
(-1525 -225);
DISPLAY 0.978723 (-1525 -225);
PAINT WHITE (-1525 -225);
DISPLAY INVISIBLE (-1525 -225);
FORCEPROP 1 LAST TOLERANCE 1%
J 0
(-1475 -475);
DISPLAY 0.510638 (-1475 -475);
PAINT SKYBLUE (-1475 -475);
DISPLAY INVISIBLE (-1475 -475);
FORCEPROP 2 LAST CDS_LIB pure_quanta
J 0
(-1475 -375);
DISPLAY INVISIBLE (-1475 -375);
FORCEPROP 1 LAST PART_NUMBER CS24702FB06
J 0
(-1525 -275);
DISPLAY 0.510638 (-1525 -275);
PAINT WHITE (-1525 -275);
DISPLAY INVISIBLE (-1525 -275);
FORCEPROP 1 LAST LOCATION R116
J 0
(-1825 -375);
DISPLAY 0.702128 (-1825 -375);
PAINT YELLOW (-1825 -375);
FORCEPROP 0 LAST $SEC 1
J 0
(-1825 -325);
DISPLAY INVISIBLE (-1825 -325);
FORCEPROP 0 LAST CDS_SEC 1
J 0
(-1825 -325);
DISPLAY INVISIBLE (-1825 -325);
FORCEPROP 1 LASTPIN (-1575 -375) $PN 1
J 0
(-1563 -363);
DISPLAY 0.808511 (-1563 -363);
PAINT WHITE (-1563 -363);
DISPLAY INVISIBLE (-1563 -363);
FORCEPROP 1 LASTPIN (-1375 -375) $PN 2
J 0
(-1413 -363);
DISPLAY 0.808511 (-1413 -363);
PAINT WHITE (-1413 -363);
DISPLAY INVISIBLE (-1413 -363);
FORCEADD OFFPAGE..2
(5300 1750);
FORCEPROP 2 LAST $XR2 26 
J 0
(5669 1750);
DISPLAY 0.638298 (5669 1750);
PAINT MONO (5669 1750);
FORCEPROP 2 LAST $XR1 27 
J 0
(5579 1750);
DISPLAY 0.638298 (5579 1750);
PAINT MONO (5579 1750);
FORCEPROP 2 LAST $XR0 10 
J 0
(5489 1750);
DISPLAY 0.638298 (5489 1750);
PAINT MONO (5489 1750);
FORCEPROP 2 LAST PATH I310
J 0
(5500 1800);
DISPLAY 1.021277 (5500 1800);
DISPLAY INVISIBLE (5500 1800);
FORCEPROP 1 LAST COMMENT_BODY TRUE
J 0
(5255 1655);
DISPLAY 0.872340 (5255 1655);
PAINT PEACH (5255 1655);
DISPLAY INVISIBLE (5255 1655);
FORCEPROP 1 LAST OFFPAGE TRUE
J 0
(5625 1625);
DISPLAY 0.872340 (5625 1625);
PAINT GREEN (5625 1625);
DISPLAY INVISIBLE (5625 1625);
FORCEPROP 2 LAST CDS_LIB standard
J 0
(5300 1750);
DISPLAY INVISIBLE (5300 1750);
FORCEADD OFFPAGE..3
(5300 1700);
FORCEPROP 2 LAST $XR2 10 
J 0
(5694 1700);
DISPLAY 0.638298 (5694 1700);
PAINT MONO (5694 1700);
FORCEPROP 2 LAST $XR1 27 
J 0
(5604 1700);
DISPLAY 0.638298 (5604 1700);
PAINT MONO (5604 1700);
FORCEPROP 2 LAST $XR0 26 
J 0
(5514 1700);
DISPLAY 0.638298 (5514 1700);
PAINT MONO (5514 1700);
FORCEPROP 2 LAST PATH I311
J 0
(5525 1750);
DISPLAY 1.021277 (5525 1750);
DISPLAY INVISIBLE (5525 1750);
FORCEPROP 1 LAST COMMENT_BODY TRUE
J 0
(5250 1600);
DISPLAY 0.872340 (5250 1600);
PAINT PEACH (5250 1600);
DISPLAY INVISIBLE (5250 1600);
FORCEPROP 1 LAST OFFPAGE TRUE
J 0
(5625 1575);
DISPLAY 0.872340 (5625 1575);
PAINT GREEN (5625 1575);
DISPLAY INVISIBLE (5625 1575);
FORCEPROP 2 LAST CDS_LIB standard
J 0
(5300 1700);
DISPLAY INVISIBLE (5300 1700);
FORCEADD OFFPAGE..2
(5300 1650);
FORCEPROP 2 LAST $XR1 27 
J 0
(5579 1650);
DISPLAY 0.638298 (5579 1650);
PAINT MONO (5579 1650);
FORCEPROP 2 LAST $XR0 10 
J 0
(5489 1650);
DISPLAY 0.638298 (5489 1650);
PAINT MONO (5489 1650);
FORCEPROP 2 LAST PATH I312
J 0
(5500 1700);
DISPLAY 1.021277 (5500 1700);
DISPLAY INVISIBLE (5500 1700);
FORCEPROP 1 LAST COMMENT_BODY TRUE
J 0
(5255 1555);
DISPLAY 0.872340 (5255 1555);
PAINT PEACH (5255 1555);
DISPLAY INVISIBLE (5255 1555);
FORCEPROP 1 LAST OFFPAGE TRUE
J 0
(5625 1525);
DISPLAY 0.872340 (5625 1525);
PAINT GREEN (5625 1525);
DISPLAY INVISIBLE (5625 1525);
FORCEPROP 2 LAST CDS_LIB standard
J 0
(5300 1650);
DISPLAY INVISIBLE (5300 1650);
FORCEADD OFFPAGE..3
(5300 1600);
FORCEPROP 2 LAST $XR1 10 
J 0
(5604 1600);
DISPLAY 0.638298 (5604 1600);
PAINT MONO (5604 1600);
FORCEPROP 2 LAST $XR0 27 
J 0
(5514 1600);
DISPLAY 0.638298 (5514 1600);
PAINT MONO (5514 1600);
FORCEPROP 2 LAST PATH I313
J 0
(5525 1650);
DISPLAY 1.021277 (5525 1650);
DISPLAY INVISIBLE (5525 1650);
FORCEPROP 1 LAST COMMENT_BODY TRUE
J 0
(5250 1500);
DISPLAY 0.872340 (5250 1500);
PAINT PEACH (5250 1500);
DISPLAY INVISIBLE (5250 1500);
FORCEPROP 1 LAST OFFPAGE TRUE
J 0
(5625 1475);
DISPLAY 0.872340 (5625 1475);
PAINT GREEN (5625 1475);
DISPLAY INVISIBLE (5625 1475);
FORCEPROP 2 LAST CDS_LIB standard
J 0
(5300 1600);
DISPLAY INVISIBLE (5300 1600);
FORCEADD Q_RES..1
(4125 1700);
FORCEPROP 1 LAST VALUE 33.2
J 0
(4250 1700);
DISPLAY 0.510638 (4250 1700);
PAINT SKYBLUE (4250 1700);
FORCEPROP 1 LAST MATERIAL CHIP
J 2
(4500 1700);
DISPLAY 0.510638 (4500 1700);
PAINT SKYBLUE (4500 1700);
FORCEPROP 1 LAST PACK_TYPE 0402LF
J 0
(4375 1550);
DISPLAY 0.510638 (4375 1550);
PAINT SKYBLUE (4375 1550);
DISPLAY INVISIBLE (4375 1550);
FORCEPROP 1 LAST WATTAGE 1/16W
J 2
(4100 1550);
DISPLAY 0.510638 (4100 1550);
PAINT SKYBLUE (4100 1550);
DISPLAY INVISIBLE (4100 1550);
FORCEPROP 1 LAST PATH I314
J 0
(4075 1850);
DISPLAY 0.978723 (4075 1850);
PAINT WHITE (4075 1850);
DISPLAY INVISIBLE (4075 1850);
FORCEPROP 2 LAST CDS_LIB pure_quanta
J 0
(4125 1700);
DISPLAY INVISIBLE (4125 1700);
FORCEPROP 1 LAST PART_NUMBER CS03322FB03
J 0
(4075 1800);
DISPLAY 0.510638 (4075 1800);
PAINT WHITE (4075 1800);
DISPLAY INVISIBLE (4075 1800);
FORCEPROP 1 LAST TOLERANCE 1%
J 0
(4250 1700);
DISPLAY 0.510638 (4250 1700);
PAINT SKYBLUE (4250 1700);
DISPLAY INVISIBLE (4250 1700);
FORCEPROP 1 LAST LOCATION R394
J 2
(3950 1700);
DISPLAY 0.702128 (3950 1700);
PAINT YELLOW (3950 1700);
FORCEPROP 1 LASTPIN (4025 1700) $PN 1
J 0
(4037 1712);
DISPLAY 0.808511 (4037 1712);
PAINT WHITE (4037 1712);
FORCEPROP 1 LASTPIN (4225 1700) $PN 2
J 0
(4187 1712);
DISPLAY 0.808511 (4187 1712);
PAINT WHITE (4187 1712);
FORCEPROP 0 LAST $SEC 1
J 0
(4225 1750);
DISPLAY 0.680851 (4225 1750);
PAINT MONO (4225 1750);
DISPLAY INVISIBLE (4225 1750);
FORCEPROP 0 LAST CDS_SEC 1
J 0
(4225 1750);
DISPLAY 0.680851 (4225 1750);
DISPLAY INVISIBLE (4225 1750);
FORCEADD Q_RES..1
(4125 1750);
FORCEPROP 1 LAST VALUE 33.2
J 0
(4250 1750);
DISPLAY 0.510638 (4250 1750);
PAINT SKYBLUE (4250 1750);
FORCEPROP 1 LAST MATERIAL CHIP
J 2
(4500 1750);
DISPLAY 0.510638 (4500 1750);
PAINT SKYBLUE (4500 1750);
FORCEPROP 1 LAST PACK_TYPE 0402LF
J 0
(4375 1600);
DISPLAY 0.510638 (4375 1600);
PAINT SKYBLUE (4375 1600);
DISPLAY INVISIBLE (4375 1600);
FORCEPROP 1 LAST WATTAGE 1/16W
J 2
(4100 1600);
DISPLAY 0.510638 (4100 1600);
PAINT SKYBLUE (4100 1600);
DISPLAY INVISIBLE (4100 1600);
FORCEPROP 1 LAST PATH I315
J 0
(4075 1900);
DISPLAY 0.978723 (4075 1900);
PAINT WHITE (4075 1900);
DISPLAY INVISIBLE (4075 1900);
FORCEPROP 2 LAST CDS_LIB pure_quanta
J 0
(4125 1750);
DISPLAY INVISIBLE (4125 1750);
FORCEPROP 1 LAST PART_NUMBER CS03322FB03
J 0
(4075 1850);
DISPLAY 0.510638 (4075 1850);
PAINT WHITE (4075 1850);
DISPLAY INVISIBLE (4075 1850);
FORCEPROP 1 LAST TOLERANCE 1%
J 0
(4250 1750);
DISPLAY 0.510638 (4250 1750);
PAINT SKYBLUE (4250 1750);
DISPLAY INVISIBLE (4250 1750);
FORCEPROP 1 LAST LOCATION R165
J 2
(3950 1750);
DISPLAY 0.702128 (3950 1750);
PAINT YELLOW (3950 1750);
FORCEPROP 0 LAST $SEC 1
J 0
(3875 1800);
DISPLAY 0.680851 (3875 1800);
PAINT MONO (3875 1800);
DISPLAY INVISIBLE (3875 1800);
FORCEPROP 0 LAST CDS_SEC 1
J 0
(3875 1800);
DISPLAY 1.021277 (3875 1800);
DISPLAY INVISIBLE (3875 1800);
FORCEPROP 1 LASTPIN (4025 1750) $PN 1
J 0
(4037 1762);
DISPLAY 0.808511 (4037 1762);
PAINT WHITE (4037 1762);
DISPLAY INVISIBLE (4037 1762);
FORCEPROP 1 LASTPIN (4225 1750) $PN 2
J 0
(4187 1762);
DISPLAY 0.808511 (4187 1762);
PAINT WHITE (4187 1762);
DISPLAY INVISIBLE (4187 1762);
FORCEADD Q_RES..1
(4125 1650);
FORCEPROP 1 LAST VALUE 33.2
J 0
(4250 1650);
DISPLAY 0.510638 (4250 1650);
PAINT SKYBLUE (4250 1650);
FORCEPROP 1 LAST MATERIAL CHIP
J 2
(4500 1650);
DISPLAY 0.510638 (4500 1650);
PAINT SKYBLUE (4500 1650);
FORCEPROP 1 LAST PACK_TYPE 0402LF
J 0
(4375 1500);
DISPLAY 0.510638 (4375 1500);
PAINT SKYBLUE (4375 1500);
DISPLAY INVISIBLE (4375 1500);
FORCEPROP 1 LAST WATTAGE 1/16W
J 2
(4100 1500);
DISPLAY 0.510638 (4100 1500);
PAINT SKYBLUE (4100 1500);
DISPLAY INVISIBLE (4100 1500);
FORCEPROP 1 LAST PATH I316
J 0
(4075 1800);
DISPLAY 0.978723 (4075 1800);
PAINT WHITE (4075 1800);
DISPLAY INVISIBLE (4075 1800);
FORCEPROP 2 LAST CDS_LIB pure_quanta
J 0
(4125 1650);
DISPLAY INVISIBLE (4125 1650);
FORCEPROP 1 LAST PART_NUMBER CS03322FB03
J 0
(4075 1750);
DISPLAY 0.510638 (4075 1750);
PAINT WHITE (4075 1750);
DISPLAY INVISIBLE (4075 1750);
FORCEPROP 1 LAST TOLERANCE 1%
J 0
(4250 1650);
DISPLAY 0.510638 (4250 1650);
PAINT SKYBLUE (4250 1650);
DISPLAY INVISIBLE (4250 1650);
FORCEPROP 1 LAST LOCATION R589
J 2
(3950 1650);
DISPLAY 0.702128 (3950 1650);
PAINT YELLOW (3950 1650);
FORCEPROP 0 LAST $SEC 1
J 0
(3875 1700);
DISPLAY 0.680851 (3875 1700);
PAINT MONO (3875 1700);
DISPLAY INVISIBLE (3875 1700);
FORCEPROP 0 LAST CDS_SEC 1
J 0
(3875 1700);
DISPLAY 1.021277 (3875 1700);
DISPLAY INVISIBLE (3875 1700);
FORCEPROP 1 LASTPIN (4025 1650) $PN 1
J 0
(4037 1662);
DISPLAY 0.808511 (4037 1662);
PAINT WHITE (4037 1662);
DISPLAY INVISIBLE (4037 1662);
FORCEPROP 1 LASTPIN (4225 1650) $PN 2
J 0
(4187 1662);
DISPLAY 0.808511 (4187 1662);
PAINT WHITE (4187 1662);
DISPLAY INVISIBLE (4187 1662);
FORCEADD Q_RES..1
(4125 1600);
FORCEPROP 1 LAST MATERIAL CHIP
J 2
(4500 1600);
DISPLAY 0.510638 (4500 1600);
PAINT SKYBLUE (4500 1600);
FORCEPROP 1 LAST VALUE 33.2
J 0
(4250 1600);
DISPLAY 0.510638 (4250 1600);
PAINT SKYBLUE (4250 1600);
FORCEPROP 1 LAST PACK_TYPE 0402LF
J 0
(4375 1450);
DISPLAY 0.510638 (4375 1450);
PAINT SKYBLUE (4375 1450);
DISPLAY INVISIBLE (4375 1450);
FORCEPROP 1 LAST WATTAGE 1/16W
J 2
(4100 1450);
DISPLAY 0.510638 (4100 1450);
PAINT SKYBLUE (4100 1450);
DISPLAY INVISIBLE (4100 1450);
FORCEPROP 1 LAST PATH I317
J 0
(4075 1750);
DISPLAY 0.978723 (4075 1750);
PAINT WHITE (4075 1750);
DISPLAY INVISIBLE (4075 1750);
FORCEPROP 2 LAST CDS_LIB pure_quanta
J 0
(4125 1600);
DISPLAY INVISIBLE (4125 1600);
FORCEPROP 1 LAST PART_NUMBER CS03322FB03
J 0
(4075 1700);
DISPLAY 0.510638 (4075 1700);
PAINT WHITE (4075 1700);
DISPLAY INVISIBLE (4075 1700);
FORCEPROP 1 LAST TOLERANCE 1%
J 0
(4250 1600);
DISPLAY 0.510638 (4250 1600);
PAINT SKYBLUE (4250 1600);
DISPLAY INVISIBLE (4250 1600);
FORCEPROP 1 LAST LOCATION R590
J 2
(3950 1600);
DISPLAY 0.702128 (3950 1600);
PAINT YELLOW (3950 1600);
FORCEPROP 1 LASTPIN (4025 1600) $PN 1
J 0
(4037 1612);
DISPLAY 0.808511 (4037 1612);
PAINT WHITE (4037 1612);
FORCEPROP 1 LASTPIN (4225 1600) $PN 2
J 0
(4187 1612);
DISPLAY 0.808511 (4187 1612);
PAINT WHITE (4187 1612);
FORCEPROP 0 LAST $SEC 1
J 0
(4225 1650);
DISPLAY 0.680851 (4225 1650);
PAINT MONO (4225 1650);
DISPLAY INVISIBLE (4225 1650);
FORCEPROP 0 LAST CDS_SEC 1
J 0
(4225 1650);
DISPLAY 0.680851 (4225 1650);
DISPLAY INVISIBLE (4225 1650);
FORCEADD Q_RES..1
(2075 -1000);
FORCEPROP 1 LAST MATERIAL CHIP
J 2
(2450 -1000);
DISPLAY 0.510638 (2450 -1000);
PAINT SKYBLUE (2450 -1000);
FORCEPROP 1 LAST VALUE 33.2
J 0
(2200 -1000);
DISPLAY 0.510638 (2200 -1000);
PAINT SKYBLUE (2200 -1000);
FORCEPROP 1 LAST PACK_TYPE 0402LF
J 0
(2325 -1150);
DISPLAY 0.510638 (2325 -1150);
PAINT SKYBLUE (2325 -1150);
DISPLAY INVISIBLE (2325 -1150);
FORCEPROP 1 LAST WATTAGE 1/16W
J 2
(2050 -1150);
DISPLAY 0.510638 (2050 -1150);
PAINT SKYBLUE (2050 -1150);
DISPLAY INVISIBLE (2050 -1150);
FORCEPROP 1 LAST PATH I318
J 0
(2025 -850);
DISPLAY 0.978723 (2025 -850);
PAINT WHITE (2025 -850);
DISPLAY INVISIBLE (2025 -850);
FORCEPROP 2 LAST CDS_LIB pure_quanta
J 0
(2075 -1000);
DISPLAY INVISIBLE (2075 -1000);
FORCEPROP 1 LAST PART_NUMBER CS03322FB03
J 0
(2025 -900);
DISPLAY 0.510638 (2025 -900);
PAINT WHITE (2025 -900);
DISPLAY INVISIBLE (2025 -900);
FORCEPROP 1 LAST TOLERANCE 1%
J 0
(2200 -1000);
DISPLAY 0.510638 (2200 -1000);
PAINT SKYBLUE (2200 -1000);
DISPLAY INVISIBLE (2200 -1000);
FORCEPROP 1 LAST LOCATION R582
J 2
(1900 -1000);
DISPLAY 0.702128 (1900 -1000);
PAINT YELLOW (1900 -1000);
FORCEPROP 1 LASTPIN (1975 -1000) $PN 1
J 0
(1987 -988);
DISPLAY 0.808511 (1987 -988);
PAINT WHITE (1987 -988);
FORCEPROP 1 LASTPIN (2175 -1000) $PN 2
J 0
(2137 -988);
DISPLAY 0.808511 (2137 -988);
PAINT WHITE (2137 -988);
FORCEPROP 0 LAST $SEC 1
J 0
(2175 -950);
DISPLAY 0.680851 (2175 -950);
PAINT MONO (2175 -950);
DISPLAY INVISIBLE (2175 -950);
FORCEPROP 0 LAST CDS_SEC 1
J 0
(2175 -950);
DISPLAY 0.680851 (2175 -950);
DISPLAY INVISIBLE (2175 -950);
FORCEADD Q_RES..1
(2075 -1050);
FORCEPROP 1 LAST MATERIAL CHIP
J 2
(2450 -1050);
DISPLAY 0.510638 (2450 -1050);
PAINT SKYBLUE (2450 -1050);
FORCEPROP 1 LAST VALUE 33.2
J 0
(2200 -1050);
DISPLAY 0.510638 (2200 -1050);
PAINT SKYBLUE (2200 -1050);
FORCEPROP 1 LAST PACK_TYPE 0402LF
J 0
(2325 -1200);
DISPLAY 0.510638 (2325 -1200);
PAINT SKYBLUE (2325 -1200);
DISPLAY INVISIBLE (2325 -1200);
FORCEPROP 1 LAST WATTAGE 1/16W
J 2
(2050 -1200);
DISPLAY 0.510638 (2050 -1200);
PAINT SKYBLUE (2050 -1200);
DISPLAY INVISIBLE (2050 -1200);
FORCEPROP 1 LAST PATH I319
J 0
(2025 -900);
DISPLAY 0.978723 (2025 -900);
PAINT WHITE (2025 -900);
DISPLAY INVISIBLE (2025 -900);
FORCEPROP 2 LAST CDS_LIB pure_quanta
J 0
(2075 -1050);
DISPLAY INVISIBLE (2075 -1050);
FORCEPROP 1 LAST PART_NUMBER CS03322FB03
J 0
(2025 -950);
DISPLAY 0.510638 (2025 -950);
PAINT WHITE (2025 -950);
DISPLAY INVISIBLE (2025 -950);
FORCEPROP 1 LAST TOLERANCE 1%
J 0
(2200 -1050);
DISPLAY 0.510638 (2200 -1050);
PAINT SKYBLUE (2200 -1050);
DISPLAY INVISIBLE (2200 -1050);
FORCEPROP 1 LAST LOCATION R583
J 2
(1900 -1050);
DISPLAY 0.702128 (1900 -1050);
PAINT YELLOW (1900 -1050);
FORCEPROP 0 LAST $SEC 1
J 0
(1825 -1000);
DISPLAY 0.680851 (1825 -1000);
PAINT MONO (1825 -1000);
DISPLAY INVISIBLE (1825 -1000);
FORCEPROP 0 LAST CDS_SEC 1
J 0
(1825 -1000);
DISPLAY 1.021277 (1825 -1000);
DISPLAY INVISIBLE (1825 -1000);
FORCEPROP 1 LASTPIN (1975 -1050) $PN 1
J 0
(1987 -1038);
DISPLAY 0.808511 (1987 -1038);
PAINT WHITE (1987 -1038);
DISPLAY INVISIBLE (1987 -1038);
FORCEPROP 1 LASTPIN (2175 -1050) $PN 2
J 0
(2137 -1038);
DISPLAY 0.808511 (2137 -1038);
PAINT WHITE (2137 -1038);
DISPLAY INVISIBLE (2137 -1038);
FORCEADD Q_RES..1
(2075 -1100);
FORCEPROP 1 LAST MATERIAL CHIP
J 2
(2450 -1100);
DISPLAY 0.510638 (2450 -1100);
PAINT SKYBLUE (2450 -1100);
FORCEPROP 1 LAST VALUE 33.2
J 0
(2200 -1100);
DISPLAY 0.510638 (2200 -1100);
PAINT SKYBLUE (2200 -1100);
FORCEPROP 1 LAST PACK_TYPE 0402LF
J 0
(2325 -1250);
DISPLAY 0.510638 (2325 -1250);
PAINT SKYBLUE (2325 -1250);
DISPLAY INVISIBLE (2325 -1250);
FORCEPROP 1 LAST WATTAGE 1/16W
J 2
(2050 -1250);
DISPLAY 0.510638 (2050 -1250);
PAINT SKYBLUE (2050 -1250);
DISPLAY INVISIBLE (2050 -1250);
FORCEPROP 1 LAST PATH I320
J 0
(2025 -950);
DISPLAY 0.978723 (2025 -950);
PAINT WHITE (2025 -950);
DISPLAY INVISIBLE (2025 -950);
FORCEPROP 2 LAST CDS_LIB pure_quanta
J 0
(2075 -1100);
DISPLAY INVISIBLE (2075 -1100);
FORCEPROP 1 LAST PART_NUMBER CS03322FB03
J 0
(2025 -1000);
DISPLAY 0.510638 (2025 -1000);
PAINT WHITE (2025 -1000);
DISPLAY INVISIBLE (2025 -1000);
FORCEPROP 1 LAST TOLERANCE 1%
J 0
(2200 -1100);
DISPLAY 0.510638 (2200 -1100);
PAINT SKYBLUE (2200 -1100);
DISPLAY INVISIBLE (2200 -1100);
FORCEPROP 1 LAST LOCATION R584
J 2
(1900 -1100);
DISPLAY 0.702128 (1900 -1100);
PAINT YELLOW (1900 -1100);
FORCEPROP 1 LASTPIN (1975 -1100) $PN 1
J 0
(1987 -1088);
DISPLAY 0.808511 (1987 -1088);
PAINT WHITE (1987 -1088);
FORCEPROP 1 LASTPIN (2175 -1100) $PN 2
J 0
(2137 -1088);
DISPLAY 0.808511 (2137 -1088);
PAINT WHITE (2137 -1088);
FORCEPROP 0 LAST $SEC 1
J 0
(2175 -1050);
DISPLAY 0.680851 (2175 -1050);
PAINT MONO (2175 -1050);
DISPLAY INVISIBLE (2175 -1050);
FORCEPROP 0 LAST CDS_SEC 1
J 0
(2175 -1050);
DISPLAY 0.680851 (2175 -1050);
DISPLAY INVISIBLE (2175 -1050);
FORCEADD Q_RES..1
(2075 -950);
FORCEPROP 1 LAST MATERIAL CHIP
J 2
(2450 -950);
DISPLAY 0.510638 (2450 -950);
PAINT SKYBLUE (2450 -950);
FORCEPROP 1 LAST VALUE 33.2
J 0
(2200 -950);
DISPLAY 0.510638 (2200 -950);
PAINT SKYBLUE (2200 -950);
FORCEPROP 1 LAST PACK_TYPE 0402LF
J 0
(2325 -1100);
DISPLAY 0.510638 (2325 -1100);
PAINT SKYBLUE (2325 -1100);
DISPLAY INVISIBLE (2325 -1100);
FORCEPROP 1 LAST WATTAGE 1/16W
J 2
(2050 -1100);
DISPLAY 0.510638 (2050 -1100);
PAINT SKYBLUE (2050 -1100);
DISPLAY INVISIBLE (2050 -1100);
FORCEPROP 1 LAST PATH I321
J 0
(2025 -800);
DISPLAY 0.978723 (2025 -800);
PAINT WHITE (2025 -800);
DISPLAY INVISIBLE (2025 -800);
FORCEPROP 2 LAST CDS_LIB pure_quanta
J 0
(2075 -950);
DISPLAY INVISIBLE (2075 -950);
FORCEPROP 1 LAST PART_NUMBER CS03322FB03
J 0
(2025 -850);
DISPLAY 0.510638 (2025 -850);
PAINT WHITE (2025 -850);
DISPLAY INVISIBLE (2025 -850);
FORCEPROP 1 LAST TOLERANCE 1%
J 0
(2200 -950);
DISPLAY 0.510638 (2200 -950);
PAINT SKYBLUE (2200 -950);
DISPLAY INVISIBLE (2200 -950);
FORCEPROP 1 LAST LOCATION R580
J 2
(1900 -950);
DISPLAY 0.702128 (1900 -950);
PAINT YELLOW (1900 -950);
FORCEPROP 0 LAST $SEC 1
J 0
(1825 -900);
DISPLAY 0.680851 (1825 -900);
PAINT MONO (1825 -900);
DISPLAY INVISIBLE (1825 -900);
FORCEPROP 0 LAST CDS_SEC 1
J 0
(1825 -900);
DISPLAY 1.021277 (1825 -900);
DISPLAY INVISIBLE (1825 -900);
FORCEPROP 1 LASTPIN (1975 -950) $PN 1
J 0
(1987 -938);
DISPLAY 0.808511 (1987 -938);
PAINT WHITE (1987 -938);
DISPLAY INVISIBLE (1987 -938);
FORCEPROP 1 LASTPIN (2175 -950) $PN 2
J 0
(2137 -938);
DISPLAY 0.808511 (2137 -938);
PAINT WHITE (2137 -938);
DISPLAY INVISIBLE (2137 -938);
FORCEADD OFFPAGE..2
(3525 -1050);
FORCEPROP 2 LAST $XR1 10 
J 0
(3804 -1050);
DISPLAY 0.638298 (3804 -1050);
PAINT MONO (3804 -1050);
FORCEPROP 2 LAST $XR0 27 
J 0
(3714 -1050);
DISPLAY 0.638298 (3714 -1050);
PAINT MONO (3714 -1050);
FORCEPROP 2 LAST PATH I322
J 0
(3825 -1000);
DISPLAY 1.021277 (3825 -1000);
DISPLAY INVISIBLE (3825 -1000);
FORCEPROP 1 LAST COMMENT_BODY TRUE
J 0
(3480 -1145);
DISPLAY 0.872340 (3480 -1145);
PAINT PEACH (3480 -1145);
DISPLAY INVISIBLE (3480 -1145);
FORCEPROP 1 LAST OFFPAGE TRUE
J 0
(3850 -1175);
DISPLAY 0.872340 (3850 -1175);
PAINT GREEN (3850 -1175);
DISPLAY INVISIBLE (3850 -1175);
FORCEPROP 2 LAST CDS_LIB standard
J 0
(3525 -1050);
DISPLAY INVISIBLE (3525 -1050);
FORCEADD OFFPAGE..3
(3525 -1100);
FORCEPROP 2 LAST $XR0 10 
J 0
(3739 -1100);
DISPLAY 0.638298 (3739 -1100);
PAINT MONO (3739 -1100);
FORCEPROP 2 LAST $XR1 27 
J 0
(3829 -1100);
DISPLAY 0.638298 (3829 -1100);
PAINT MONO (3829 -1100);
FORCEPROP 2 LAST PATH I323
J 0
(3800 -1050);
DISPLAY 1.021277 (3800 -1050);
DISPLAY INVISIBLE (3800 -1050);
FORCEPROP 1 LAST COMMENT_BODY TRUE
J 0
(3475 -1200);
DISPLAY 0.872340 (3475 -1200);
PAINT PEACH (3475 -1200);
DISPLAY INVISIBLE (3475 -1200);
FORCEPROP 1 LAST OFFPAGE TRUE
J 0
(3850 -1225);
DISPLAY 0.872340 (3850 -1225);
PAINT GREEN (3850 -1225);
DISPLAY INVISIBLE (3850 -1225);
FORCEPROP 2 LAST CDS_LIB standard
J 0
(3525 -1100);
DISPLAY INVISIBLE (3525 -1100);
FORCEADD OFFPAGE..2
(3525 -950);
FORCEPROP 2 LAST $XR0 27 
J 0
(3714 -950);
DISPLAY 0.638298 (3714 -950);
PAINT MONO (3714 -950);
FORCEPROP 2 LAST $XR1 10 
J 0
(3804 -950);
DISPLAY 0.638298 (3804 -950);
PAINT MONO (3804 -950);
FORCEPROP 2 LAST PATH I324
J 0
(3825 -900);
DISPLAY 1.021277 (3825 -900);
DISPLAY INVISIBLE (3825 -900);
FORCEPROP 1 LAST COMMENT_BODY TRUE
J 0
(3480 -1045);
DISPLAY 0.872340 (3480 -1045);
PAINT PEACH (3480 -1045);
DISPLAY INVISIBLE (3480 -1045);
FORCEPROP 1 LAST OFFPAGE TRUE
J 0
(3850 -1075);
DISPLAY 0.872340 (3850 -1075);
PAINT GREEN (3850 -1075);
DISPLAY INVISIBLE (3850 -1075);
FORCEPROP 2 LAST CDS_LIB standard
J 0
(3525 -950);
DISPLAY INVISIBLE (3525 -950);
FORCEADD OFFPAGE..3
(3525 -1000);
FORCEPROP 2 LAST $XR1 27 
J 0
(3829 -1000);
DISPLAY 0.638298 (3829 -1000);
PAINT MONO (3829 -1000);
FORCEPROP 2 LAST $XR0 10 
J 0
(3739 -1000);
DISPLAY 0.638298 (3739 -1000);
PAINT MONO (3739 -1000);
FORCEPROP 2 LAST PATH I325
J 0
(3800 -950);
DISPLAY 1.021277 (3800 -950);
DISPLAY INVISIBLE (3800 -950);
FORCEPROP 1 LAST COMMENT_BODY TRUE
J 0
(3475 -1100);
DISPLAY 0.872340 (3475 -1100);
PAINT PEACH (3475 -1100);
DISPLAY INVISIBLE (3475 -1100);
FORCEPROP 1 LAST OFFPAGE TRUE
J 0
(3850 -1125);
DISPLAY 0.872340 (3850 -1125);
PAINT GREEN (3850 -1125);
DISPLAY INVISIBLE (3850 -1125);
FORCEPROP 2 LAST CDS_LIB standard
J 0
(3525 -1000);
DISPLAY INVISIBLE (3525 -1000);
FORCEADD OFFPAGE..3
(5300 850);
FORCEPROP 2 LAST $XR0 12 
J 0
(5514 850);
DISPLAY 0.638298 (5514 850);
PAINT MONO (5514 850);
FORCEPROP 2 LAST PATH I326
J 0
(5500 925);
DISPLAY 1.021277 (5500 925);
DISPLAY INVISIBLE (5500 925);
FORCEPROP 1 LAST COMMENT_BODY TRUE
J 0
(5250 750);
DISPLAY 0.872340 (5250 750);
PAINT PEACH (5250 750);
DISPLAY INVISIBLE (5250 750);
FORCEPROP 1 LAST OFFPAGE TRUE
J 0
(5625 725);
DISPLAY 0.872340 (5625 725);
PAINT GREEN (5625 725);
DISPLAY INVISIBLE (5625 725);
FORCEPROP 2 LAST CDS_LIB standard
J 0
(5300 850);
DISPLAY INVISIBLE (5300 850);
FORCEADD OFFPAGE..3
(5300 750);
FORCEPROP 2 LAST $XR0 12 
J 0
(5514 750);
DISPLAY 0.638298 (5514 750);
PAINT MONO (5514 750);
FORCEPROP 2 LAST PATH I329
J 0
(5500 825);
DISPLAY 1.021277 (5500 825);
DISPLAY INVISIBLE (5500 825);
FORCEPROP 1 LAST COMMENT_BODY TRUE
J 0
(5250 650);
DISPLAY 0.872340 (5250 650);
PAINT PEACH (5250 650);
DISPLAY INVISIBLE (5250 650);
FORCEPROP 1 LAST OFFPAGE TRUE
J 0
(5625 625);
DISPLAY 0.872340 (5625 625);
PAINT GREEN (5625 625);
DISPLAY INVISIBLE (5625 625);
FORCEPROP 2 LAST CDS_LIB standard
J 0
(5300 750);
DISPLAY INVISIBLE (5300 750);
FORCEADD Q_RES..1
(-850 1950);
FORCEPROP 1 LAST PART_NUMBER CS03322FB03
J 0
(-950 1900);
DISPLAY 0.510638 (-950 1900);
PAINT WHITE (-950 1900);
FORCEPROP 1 LAST MATERIAL CHIP
J 0
(-1150 1950);
DISPLAY 0.510638 (-1150 1950);
PAINT SKYBLUE (-1150 1950);
FORCEPROP 1 LAST TOLERANCE 1%
J 0
(-475 1900);
DISPLAY 0.510638 (-475 1900);
PAINT SKYBLUE (-475 1900);
FORCEPROP 1 LAST WATTAGE 1/16W
J 2
(-525 1900);
DISPLAY 0.510638 (-525 1900);
PAINT SKYBLUE (-525 1900);
FORCEPROP 1 LAST VALUE 33.2
J 0
(-750 1950);
DISPLAY 0.510638 (-750 1950);
PAINT SKYBLUE (-750 1950);
FORCEPROP 1 LAST PACK_TYPE 0402LF
J 0
(-600 1800);
DISPLAY 0.510638 (-600 1800);
PAINT SKYBLUE (-600 1800);
DISPLAY INVISIBLE (-600 1800);
FORCEPROP 1 LAST PATH I33
J 0
(-900 2100);
DISPLAY 0.978723 (-900 2100);
PAINT WHITE (-900 2100);
DISPLAY INVISIBLE (-900 2100);
FORCEPROP 2 LAST CDS_LIB pure_quanta
J 0
(-850 1950);
DISPLAY INVISIBLE (-850 1950);
FORCEPROP 1 LAST LOCATION R120
J 0
(-1050 1950);
DISPLAY 0.702128 (-1050 1950);
PAINT YELLOW (-1050 1950);
FORCEPROP 1 LASTPIN (-950 1950) $PN 1
J 0
(-938 1962);
DISPLAY 0.808511 (-938 1962);
PAINT WHITE (-938 1962);
FORCEPROP 1 LASTPIN (-750 1950) $PN 2
J 0
(-788 1962);
DISPLAY 0.808511 (-788 1962);
PAINT WHITE (-788 1962);
FORCEPROP 2 LAST $SEC 1
J 0
(-900 2150);
DISPLAY 0.680851 (-900 2150);
PAINT MONO (-900 2150);
DISPLAY INVISIBLE (-900 2150);
FORCEPROP 0 LAST CDS_SEC 1
J 0
(-900 2150);
DISPLAY 0.680851 (-900 2150);
PAINT MONO (-900 2150);
DISPLAY INVISIBLE (-900 2150);
FORCEADD OFFPAGE..4
(5875 -450);
FORCEPROP 2 LAST $XR0 10 
J 0
(6061 -450);
DISPLAY 0.638298 (6061 -450);
PAINT MONO (6061 -450);
FORCEPROP 2 LAST CDS_LIB standard
J 0
(5875 -450);
DISPLAY INVISIBLE (5875 -450);
FORCEPROP 1 LAST OFFPAGE TRUE
J 0
(6200 -575);
DISPLAY 0.872340 (6200 -575);
PAINT GREEN (6200 -575);
DISPLAY INVISIBLE (6200 -575);
FORCEPROP 1 LAST COMMENT_BODY TRUE
J 0
(5850 -550);
DISPLAY 0.872340 (5850 -550);
PAINT PEACH (5850 -550);
DISPLAY INVISIBLE (5850 -550);
FORCEPROP 2 LAST PATH I332
J 0
(6050 -375);
DISPLAY 1.021277 (6050 -375);
DISPLAY INVISIBLE (6050 -375);
FORCEADD OFFPAGE..2
(5300 1350);
FORCEPROP 2 LAST $XR0 12 
J 0
(5489 1350);
DISPLAY 0.638298 (5489 1350);
PAINT MONO (5489 1350);
FORCEPROP 2 LAST $XR1 27 
J 0
(5579 1350);
DISPLAY 0.638298 (5579 1350);
PAINT MONO (5579 1350);
FORCEPROP 2 LAST PATH I333
J 0
(5475 1425);
DISPLAY 1.021277 (5475 1425);
DISPLAY INVISIBLE (5475 1425);
FORCEPROP 1 LAST COMMENT_BODY TRUE
J 0
(5255 1255);
DISPLAY 0.872340 (5255 1255);
PAINT PEACH (5255 1255);
DISPLAY INVISIBLE (5255 1255);
FORCEPROP 1 LAST OFFPAGE TRUE
J 0
(5625 1225);
DISPLAY 0.872340 (5625 1225);
PAINT GREEN (5625 1225);
DISPLAY INVISIBLE (5625 1225);
FORCEPROP 2 LAST CDS_LIB standard
J 0
(5300 1350);
DISPLAY INVISIBLE (5300 1350);
FORCEADD OFFPAGE..2
(5300 1150);
FORCEPROP 2 LAST $XR0 12 
J 0
(5489 1150);
DISPLAY 0.638298 (5489 1150);
PAINT MONO (5489 1150);
FORCEPROP 2 LAST $XR1 27 
J 0
(5579 1150);
DISPLAY 0.638298 (5579 1150);
PAINT MONO (5579 1150);
FORCEPROP 2 LAST PATH I334
J 0
(5475 1225);
DISPLAY 1.021277 (5475 1225);
DISPLAY INVISIBLE (5475 1225);
FORCEPROP 1 LAST COMMENT_BODY TRUE
J 0
(5255 1055);
DISPLAY 0.872340 (5255 1055);
PAINT PEACH (5255 1055);
DISPLAY INVISIBLE (5255 1055);
FORCEPROP 1 LAST OFFPAGE TRUE
J 0
(5625 1025);
DISPLAY 0.872340 (5625 1025);
PAINT GREEN (5625 1025);
DISPLAY INVISIBLE (5625 1025);
FORCEPROP 2 LAST CDS_LIB standard
J 0
(5300 1150);
DISPLAY INVISIBLE (5300 1150);
FORCEADD OFFPAGE..2
(5300 900);
FORCEPROP 2 LAST $XR0 12 
J 0
(5489 900);
DISPLAY 0.638298 (5489 900);
PAINT MONO (5489 900);
FORCEPROP 2 LAST PATH I335
J 0
(5475 975);
DISPLAY 1.021277 (5475 975);
DISPLAY INVISIBLE (5475 975);
FORCEPROP 1 LAST COMMENT_BODY TRUE
J 0
(5255 805);
DISPLAY 0.872340 (5255 805);
PAINT PEACH (5255 805);
DISPLAY INVISIBLE (5255 805);
FORCEPROP 1 LAST OFFPAGE TRUE
J 0
(5625 775);
DISPLAY 0.872340 (5625 775);
PAINT GREEN (5625 775);
DISPLAY INVISIBLE (5625 775);
FORCEPROP 2 LAST CDS_LIB standard
J 0
(5300 900);
DISPLAY INVISIBLE (5300 900);
FORCEADD OFFPAGE..2
(5300 800);
FORCEPROP 2 LAST $XR0 12 
J 0
(5489 800);
DISPLAY 0.638298 (5489 800);
PAINT MONO (5489 800);
FORCEPROP 2 LAST PATH I336
J 0
(5475 875);
DISPLAY 1.021277 (5475 875);
DISPLAY INVISIBLE (5475 875);
FORCEPROP 1 LAST COMMENT_BODY TRUE
J 0
(5255 705);
DISPLAY 0.872340 (5255 705);
PAINT PEACH (5255 705);
DISPLAY INVISIBLE (5255 705);
FORCEPROP 1 LAST OFFPAGE TRUE
J 0
(5625 675);
DISPLAY 0.872340 (5625 675);
PAINT GREEN (5625 675);
DISPLAY INVISIBLE (5625 675);
FORCEPROP 2 LAST CDS_LIB standard
J 0
(5300 800);
DISPLAY INVISIBLE (5300 800);
FORCEADD OFFPAGE..6
(975 -1000);
FORCEPROP 2 LAST $XR0 12 
J 0
(726 -1000);
DISPLAY 0.638298 (726 -1000);
PAINT MONO (726 -1000);
FORCEPROP 2 LAST PATH I337
J 0
(1025 -925);
DISPLAY 1.021277 (1025 -925);
DISPLAY INVISIBLE (1025 -925);
FORCEPROP 1 LAST COMMENT_BODY TRUE
J 0
(1075 -1075);
DISPLAY 0.872340 (1075 -1075);
PAINT PEACH (1075 -1075);
DISPLAY INVISIBLE (1075 -1075);
FORCEPROP 1 LAST OFFPAGE TRUE
J 0
(1300 -1125);
DISPLAY 0.872340 (1300 -1125);
PAINT GREEN (1300 -1125);
DISPLAY INVISIBLE (1300 -1125);
FORCEPROP 2 LAST CDS_LIB standard
J 0
(975 -1000);
DISPLAY INVISIBLE (975 -1000);
FORCEADD OFFPAGE..1
(975 -950);
FORCEPROP 2 LAST $XR0 12 
J 0
(724 -950);
DISPLAY 0.638298 (724 -950);
PAINT MONO (724 -950);
FORCEPROP 2 LAST PATH I338
J 0
(1025 -875);
DISPLAY 1.021277 (1025 -875);
DISPLAY INVISIBLE (1025 -875);
FORCEPROP 1 LAST COMMENT_BODY TRUE
J 0
(1100 -1050);
DISPLAY 0.872340 (1100 -1050);
PAINT PEACH (1100 -1050);
DISPLAY INVISIBLE (1100 -1050);
FORCEPROP 1 LAST OFFPAGE TRUE
J 0
(1300 -1075);
DISPLAY 0.872340 (1300 -1075);
PAINT GREEN (1300 -1075);
DISPLAY INVISIBLE (1300 -1075);
FORCEPROP 2 LAST CDS_LIB standard
J 0
(975 -950);
DISPLAY INVISIBLE (975 -950);
FORCEADD OFFPAGE..1
(975 -1050);
FORCEPROP 2 LAST $XR0 12 
J 0
(724 -1050);
DISPLAY 0.638298 (724 -1050);
PAINT MONO (724 -1050);
FORCEPROP 2 LAST PATH I339
J 0
(1025 -975);
DISPLAY 1.021277 (1025 -975);
DISPLAY INVISIBLE (1025 -975);
FORCEPROP 1 LAST COMMENT_BODY TRUE
J 0
(1100 -1150);
DISPLAY 0.872340 (1100 -1150);
PAINT PEACH (1100 -1150);
DISPLAY INVISIBLE (1100 -1150);
FORCEPROP 1 LAST OFFPAGE TRUE
J 0
(1300 -1175);
DISPLAY 0.872340 (1300 -1175);
PAINT GREEN (1300 -1175);
DISPLAY INVISIBLE (1300 -1175);
FORCEPROP 2 LAST CDS_LIB standard
J 0
(975 -1050);
DISPLAY INVISIBLE (975 -1050);
FORCEADD Q_RES..1
(-850 2000);
FORCEPROP 1 LAST MATERIAL CHIP
J 0
(-1150 2000);
DISPLAY 0.510638 (-1150 2000);
PAINT SKYBLUE (-1150 2000);
FORCEPROP 1 LAST VALUE 33.2
J 0
(-750 2000);
DISPLAY 0.510638 (-750 2000);
PAINT SKYBLUE (-750 2000);
FORCEPROP 1 LAST TOLERANCE 1%
J 0
(-725 2000);
DISPLAY 0.510638 (-725 2000);
PAINT SKYBLUE (-725 2000);
DISPLAY INVISIBLE (-725 2000);
FORCEPROP 1 LAST PART_NUMBER CS03322FB03
J 0
(-900 2100);
DISPLAY 0.510638 (-900 2100);
PAINT WHITE (-900 2100);
DISPLAY INVISIBLE (-900 2100);
FORCEPROP 1 LAST WATTAGE 1/16W
J 2
(-875 1850);
DISPLAY 0.510638 (-875 1850);
PAINT SKYBLUE (-875 1850);
DISPLAY INVISIBLE (-875 1850);
FORCEPROP 1 LAST PACK_TYPE 0402LF
J 0
(-600 1850);
DISPLAY 0.510638 (-600 1850);
PAINT SKYBLUE (-600 1850);
DISPLAY INVISIBLE (-600 1850);
FORCEPROP 1 LAST PATH I34
J 0
(-900 2150);
DISPLAY 0.978723 (-900 2150);
PAINT WHITE (-900 2150);
DISPLAY INVISIBLE (-900 2150);
FORCEPROP 2 LAST CDS_LIB pure_quanta
J 0
(-850 2000);
DISPLAY INVISIBLE (-850 2000);
FORCEPROP 1 LAST LOCATION R119
J 0
(-1050 2000);
DISPLAY 0.702128 (-1050 2000);
PAINT YELLOW (-1050 2000);
FORCEPROP 1 LASTPIN (-950 2000) $PN 1
J 0
(-938 2012);
DISPLAY 0.808511 (-938 2012);
PAINT WHITE (-938 2012);
FORCEPROP 1 LASTPIN (-750 2000) $PN 2
J 0
(-788 2012);
DISPLAY 0.808511 (-788 2012);
PAINT WHITE (-788 2012);
FORCEPROP 2 LAST $SEC 1
J 0
(-900 2200);
DISPLAY 0.680851 (-900 2200);
PAINT MONO (-900 2200);
DISPLAY INVISIBLE (-900 2200);
FORCEPROP 0 LAST CDS_SEC 1
J 0
(-900 2200);
DISPLAY 0.680851 (-900 2200);
PAINT MONO (-900 2200);
DISPLAY INVISIBLE (-900 2200);
FORCEADD OFFPAGE..6
(975 -1100);
FORCEPROP 2 LAST $XR0 12 
J 0
(726 -1100);
DISPLAY 0.638298 (726 -1100);
PAINT MONO (726 -1100);
FORCEPROP 2 LAST PATH I340
J 0
(1025 -1025);
DISPLAY 1.021277 (1025 -1025);
DISPLAY INVISIBLE (1025 -1025);
FORCEPROP 1 LAST COMMENT_BODY TRUE
J 0
(1075 -1175);
DISPLAY 0.872340 (1075 -1175);
PAINT PEACH (1075 -1175);
DISPLAY INVISIBLE (1075 -1175);
FORCEPROP 1 LAST OFFPAGE TRUE
J 0
(1300 -1225);
DISPLAY 0.872340 (1300 -1225);
PAINT GREEN (1300 -1225);
DISPLAY INVISIBLE (1300 -1225);
FORCEPROP 2 LAST CDS_LIB standard
J 0
(975 -1100);
DISPLAY INVISIBLE (975 -1100);
FORCEADD UNIVERSAL_POWER..1
(-2775 3425);
FORCEPROP 3 LASTPIN (-2775 3375) SIG_NAME P3V3_AUX\g
J 0
(-2765 3385);
DISPLAY 0.659574 (-2765 3385);
PAINT MONO (-2765 3385);
DISPLAY INVISIBLE (-2765 3385);
FORCEPROP 1 LAST HDL_POWER P3V3_AUX
J 1
(-2775 3475);
DISPLAY 0.702128 (-2775 3475);
PAINT GREEN (-2775 3475);
FORCEPROP 1 LAST PATH I349
J 0
(-2725 3450);
DISPLAY 0.872340 (-2725 3450);
PAINT AQUA (-2725 3450);
DISPLAY INVISIBLE (-2725 3450);
FORCEPROP 2 LAST CDS_LIB logical_power
J 0
(-2775 3425);
DISPLAY INVISIBLE (-2775 3425);
FORCEADD UNIVERSAL_GND..1
R 5
(-800 2200);
FORCEPROP 3 LASTPIN (-750 2200) SIG_NAME GND\g
J 0
(-740 2210);
DISPLAY 0.659574 (-740 2210);
PAINT MONO (-740 2210);
DISPLAY INVISIBLE (-740 2210);
FORCEPROP 1 LAST PATH I35
R 3
J 0
(-800 2125);
DISPLAY 0.872340 (-800 2125);
PAINT AQUA (-800 2125);
DISPLAY INVISIBLE (-800 2125);
FORCEPROP 1 LAST HDL_POWER GND
R 3
J 1
(-875 2175);
DISPLAY 0.702128 (-875 2175);
PAINT GREEN (-875 2175);
DISPLAY INVISIBLE (-875 2175);
FORCEPROP 2 LAST CDS_LIB logical_power
J 0
(-800 2200);
DISPLAY INVISIBLE (-800 2200);
FORCEADD Q_RES..1
(-2550 3300);
FORCEPROP 1 LAST VALUE 4.7K
J 2
(-2350 3300);
DISPLAY 0.510638 (-2350 3300);
PAINT SKYBLUE (-2350 3300);
FORCEPROP 1 LAST MATERIAL CHIP
J 0
(-2300 3300);
DISPLAY 0.510638 (-2300 3300);
PAINT SKYBLUE (-2300 3300);
FORCEPROP 1 LAST PACK_TYPE 0402LF
J 0
(-2300 3150);
DISPLAY 0.510638 (-2300 3150);
PAINT SKYBLUE (-2300 3150);
DISPLAY INVISIBLE (-2300 3150);
FORCEPROP 1 LAST WATTAGE 1/16W
J 2
(-2575 3150);
DISPLAY 0.510638 (-2575 3150);
PAINT SKYBLUE (-2575 3150);
DISPLAY INVISIBLE (-2575 3150);
FORCEPROP 1 LAST PATH I350
J 0
(-2600 3450);
DISPLAY 0.978723 (-2600 3450);
PAINT WHITE (-2600 3450);
DISPLAY INVISIBLE (-2600 3450);
FORCEPROP 1 LAST TOLERANCE 1%
J 0
(-2550 3200);
DISPLAY 0.510638 (-2550 3200);
PAINT SKYBLUE (-2550 3200);
DISPLAY INVISIBLE (-2550 3200);
FORCEPROP 2 LAST CDS_LIB pure_quanta
J 0
(-2550 3300);
DISPLAY INVISIBLE (-2550 3300);
FORCEPROP 1 LAST PART_NUMBER CS24702FB06
J 0
(-2600 3400);
DISPLAY 0.510638 (-2600 3400);
PAINT WHITE (-2600 3400);
DISPLAY INVISIBLE (-2600 3400);
FORCEPROP 1 LAST LOCATION R62
J 2
(-2650 3300);
DISPLAY 0.702128 (-2650 3300);
PAINT YELLOW (-2650 3300);
FORCEPROP 0 LAST $SEC 1
J 0
(-2900 3350);
DISPLAY INVISIBLE (-2900 3350);
FORCEPROP 0 LAST CDS_SEC 1
J 0
(-2900 3350);
DISPLAY INVISIBLE (-2900 3350);
FORCEPROP 1 LASTPIN (-2650 3300) $PN 1
J 0
(-2638 3312);
DISPLAY 0.808511 (-2638 3312);
PAINT WHITE (-2638 3312);
DISPLAY INVISIBLE (-2638 3312);
FORCEPROP 1 LASTPIN (-2450 3300) $PN 2
J 0
(-2488 3312);
DISPLAY 0.808511 (-2488 3312);
PAINT WHITE (-2488 3312);
DISPLAY INVISIBLE (-2488 3312);
FORCEADD OFFPAGE..2
(-1250 3300);
FORCEPROP 2 LAST $XR1 13 
J 0
(-971 3300);
DISPLAY 0.638298 (-971 3300);
PAINT MONO (-971 3300);
FORCEPROP 2 LAST $XR0 34 
J 0
(-1061 3300);
DISPLAY 0.638298 (-1061 3300);
PAINT MONO (-1061 3300);
FORCEPROP 2 LAST PATH I351
J 0
(-1050 3350);
DISPLAY 1.021277 (-1050 3350);
DISPLAY INVISIBLE (-1050 3350);
FORCEPROP 1 LAST COMMENT_BODY TRUE
J 0
(-1295 3205);
DISPLAY 0.872340 (-1295 3205);
PAINT PEACH (-1295 3205);
DISPLAY INVISIBLE (-1295 3205);
FORCEPROP 1 LAST OFFPAGE TRUE
J 0
(-925 3175);
DISPLAY 0.872340 (-925 3175);
PAINT GREEN (-925 3175);
DISPLAY INVISIBLE (-925 3175);
FORCEPROP 2 LAST CDS_LIB standard
J 0
(-1250 3300);
DISPLAY INVISIBLE (-1250 3300);
FORCEADD Q_RES..1
(-850 750);
FORCEPROP 1 LAST MATERIAL CHIP
J 0
(-650 750);
DISPLAY 0.510638 (-650 750);
PAINT SKYBLUE (-650 750);
FORCEPROP 1 LAST VALUE 33.2
J 0
(-750 750);
DISPLAY 0.510638 (-750 750);
PAINT SKYBLUE (-750 750);
FORCEPROP 1 LAST PACK_TYPE 0402LF
J 0
(-600 600);
DISPLAY 0.510638 (-600 600);
PAINT SKYBLUE (-600 600);
DISPLAY INVISIBLE (-600 600);
FORCEPROP 1 LAST WATTAGE 1/16W
J 2
(-875 600);
DISPLAY 0.510638 (-875 600);
PAINT SKYBLUE (-875 600);
DISPLAY INVISIBLE (-875 600);
FORCEPROP 1 LAST PATH I353
J 0
(-900 900);
DISPLAY 0.978723 (-900 900);
PAINT WHITE (-900 900);
DISPLAY INVISIBLE (-900 900);
FORCEPROP 2 LAST CDS_LIB pure_quanta
J 0
(-850 750);
DISPLAY INVISIBLE (-850 750);
FORCEPROP 1 LAST PART_NUMBER CS03322FB03
J 0
(-900 850);
DISPLAY 0.510638 (-900 850);
PAINT WHITE (-900 850);
DISPLAY INVISIBLE (-900 850);
FORCEPROP 1 LAST TOLERANCE 1%
J 0
(-725 750);
DISPLAY 0.510638 (-725 750);
PAINT SKYBLUE (-725 750);
DISPLAY INVISIBLE (-725 750);
FORCEPROP 1 LAST LOCATION R705
J 0
(-1075 750);
DISPLAY 0.702128 (-1075 750);
PAINT YELLOW (-1075 750);
FORCEPROP 1 LASTPIN (-950 750) $PN 1
J 0
(-938 762);
DISPLAY 0.808511 (-938 762);
PAINT WHITE (-938 762);
FORCEPROP 1 LASTPIN (-750 750) $PN 2
J 0
(-788 762);
DISPLAY 0.808511 (-788 762);
PAINT WHITE (-788 762);
FORCEPROP 0 LAST $SEC 1
J 0
(-900 850);
DISPLAY 0.680851 (-900 850);
PAINT MONO (-900 850);
DISPLAY INVISIBLE (-900 850);
FORCEPROP 0 LAST CDS_SEC 1
J 0
(-900 850);
DISPLAY 0.680851 (-900 850);
DISPLAY INVISIBLE (-900 850);
FORCEADD Q_RES..1
(-2550 3225);
FORCEPROP 1 LAST MATERIAL CHIP
J 0
(-2300 3225);
DISPLAY 0.510638 (-2300 3225);
PAINT SKYBLUE (-2300 3225);
FORCEPROP 1 LAST VALUE 4.7K
J 2
(-2350 3225);
DISPLAY 0.510638 (-2350 3225);
PAINT SKYBLUE (-2350 3225);
FORCEPROP 1 LAST PACK_TYPE 0402LF
J 0
(-2300 3075);
DISPLAY 0.510638 (-2300 3075);
PAINT SKYBLUE (-2300 3075);
DISPLAY INVISIBLE (-2300 3075);
FORCEPROP 1 LAST WATTAGE 1/16W
J 2
(-2575 3075);
DISPLAY 0.510638 (-2575 3075);
PAINT SKYBLUE (-2575 3075);
DISPLAY INVISIBLE (-2575 3075);
FORCEPROP 1 LAST PATH I354
J 0
(-2600 3375);
DISPLAY 0.978723 (-2600 3375);
PAINT WHITE (-2600 3375);
DISPLAY INVISIBLE (-2600 3375);
FORCEPROP 1 LAST TOLERANCE 1%
J 0
(-2550 3125);
DISPLAY 0.510638 (-2550 3125);
PAINT SKYBLUE (-2550 3125);
DISPLAY INVISIBLE (-2550 3125);
FORCEPROP 2 LAST CDS_LIB pure_quanta
J 0
(-2550 3225);
DISPLAY INVISIBLE (-2550 3225);
FORCEPROP 1 LAST PART_NUMBER CS24702FB06
J 0
(-2600 3325);
DISPLAY 0.510638 (-2600 3325);
PAINT WHITE (-2600 3325);
DISPLAY INVISIBLE (-2600 3325);
FORCEPROP 1 LAST LOCATION R706
J 2
(-2650 3225);
DISPLAY 0.702128 (-2650 3225);
PAINT YELLOW (-2650 3225);
FORCEPROP 0 LAST $SEC 1
J 0
(-2900 3275);
DISPLAY INVISIBLE (-2900 3275);
FORCEPROP 0 LAST CDS_SEC 1
J 0
(-2900 3275);
DISPLAY INVISIBLE (-2900 3275);
FORCEPROP 1 LASTPIN (-2650 3225) $PN 1
J 0
(-2638 3237);
DISPLAY 0.808511 (-2638 3237);
PAINT WHITE (-2638 3237);
DISPLAY INVISIBLE (-2638 3237);
FORCEPROP 1 LASTPIN (-2450 3225) $PN 2
J 0
(-2488 3237);
DISPLAY 0.808511 (-2488 3237);
PAINT WHITE (-2488 3237);
DISPLAY INVISIBLE (-2488 3237);
FORCEADD OFFPAGE..2
(-1250 3225);
FORCEPROP 2 LAST $XR0 34 
J 0
(-1061 3225);
DISPLAY 0.638298 (-1061 3225);
PAINT MONO (-1061 3225);
FORCEPROP 2 LAST $XR1 12 
J 0
(-971 3225);
DISPLAY 0.638298 (-971 3225);
PAINT MONO (-971 3225);
FORCEPROP 2 LAST PATH I355
J 0
(-1050 3275);
DISPLAY 1.021277 (-1050 3275);
DISPLAY INVISIBLE (-1050 3275);
FORCEPROP 1 LAST COMMENT_BODY TRUE
J 0
(-1295 3130);
DISPLAY 0.872340 (-1295 3130);
PAINT PEACH (-1295 3130);
DISPLAY INVISIBLE (-1295 3130);
FORCEPROP 1 LAST OFFPAGE TRUE
J 0
(-925 3100);
DISPLAY 0.872340 (-925 3100);
PAINT GREEN (-925 3100);
DISPLAY INVISIBLE (-925 3100);
FORCEPROP 2 LAST CDS_LIB standard
J 0
(-1250 3225);
DISPLAY INVISIBLE (-1250 3225);
FORCEADD OFFPAGE..3
R 2
(-350 2450);
FORCEPROP 2 LAST $XR0 20 
J 0
(-599 2450);
DISPLAY 0.638298 (-599 2450);
PAINT MONO (-599 2450);
FORCEPROP 2 LAST PATH I36
J 0
(-575 2500);
DISPLAY 1.021277 (-575 2500);
DISPLAY INVISIBLE (-575 2500);
FORCEPROP 1 LAST COMMENT_BODY TRUE
J 2
(-300 2350);
DISPLAY 0.872340 (-300 2350);
PAINT PEACH (-300 2350);
DISPLAY INVISIBLE (-300 2350);
FORCEPROP 1 LAST OFFPAGE TRUE
J 2
(-675 2325);
DISPLAY 0.872340 (-675 2325);
PAINT GREEN (-675 2325);
DISPLAY INVISIBLE (-675 2325);
FORCEPROP 2 LAST CDS_LIB standard
J 0
(-350 2450);
DISPLAY INVISIBLE (-350 2450);
FORCEADD OFFPAGE..3
R 2
(-350 2600);
FORCEPROP 2 LAST $XR0 20 
J 0
(-599 2600);
DISPLAY 0.638298 (-599 2600);
PAINT MONO (-599 2600);
FORCEPROP 2 LAST PATH I37
J 0
(-575 2650);
DISPLAY 1.021277 (-575 2650);
DISPLAY INVISIBLE (-575 2650);
FORCEPROP 1 LAST COMMENT_BODY TRUE
J 2
(-300 2500);
DISPLAY 0.872340 (-300 2500);
PAINT PEACH (-300 2500);
DISPLAY INVISIBLE (-300 2500);
FORCEPROP 1 LAST OFFPAGE TRUE
J 2
(-675 2475);
DISPLAY 0.872340 (-675 2475);
PAINT GREEN (-675 2475);
DISPLAY INVISIBLE (-675 2475);
FORCEPROP 2 LAST CDS_LIB standard
J 0
(-350 2600);
DISPLAY INVISIBLE (-350 2600);
FORCEADD Q_RES..1
(-650 500);
FORCEPROP 1 LAST VALUE 33.2
J 0
(-525 500);
DISPLAY 0.510638 (-525 500);
PAINT SKYBLUE (-525 500);
FORCEPROP 1 LAST MATERIAL CHIP
J 2
(-275 500);
DISPLAY 0.510638 (-275 500);
PAINT SKYBLUE (-275 500);
FORCEPROP 1 LAST PACK_TYPE 0402LF
J 0
(-400 350);
DISPLAY 0.510638 (-400 350);
PAINT SKYBLUE (-400 350);
DISPLAY INVISIBLE (-400 350);
FORCEPROP 1 LAST WATTAGE 1/16W
J 2
(-675 350);
DISPLAY 0.510638 (-675 350);
PAINT SKYBLUE (-675 350);
DISPLAY INVISIBLE (-675 350);
FORCEPROP 1 LAST PATH I379
J 0
(-700 650);
DISPLAY 0.978723 (-700 650);
PAINT WHITE (-700 650);
DISPLAY INVISIBLE (-700 650);
FORCEPROP 2 LAST CDS_LIB pure_quanta
J 0
(-650 500);
DISPLAY INVISIBLE (-650 500);
FORCEPROP 1 LAST PART_NUMBER CS03322FB03
J 0
(-700 600);
DISPLAY 0.510638 (-700 600);
PAINT WHITE (-700 600);
DISPLAY INVISIBLE (-700 600);
FORCEPROP 1 LAST TOLERANCE 1%
J 0
(-525 500);
DISPLAY 0.510638 (-525 500);
PAINT SKYBLUE (-525 500);
DISPLAY INVISIBLE (-525 500);
FORCEPROP 1 LAST LOCATION R148
J 2
(-825 500);
DISPLAY 0.702128 (-825 500);
PAINT YELLOW (-825 500);
FORCEPROP 0 LAST $SEC 1
J 0
(-900 550);
DISPLAY 0.680851 (-900 550);
PAINT MONO (-900 550);
DISPLAY INVISIBLE (-900 550);
FORCEPROP 0 LAST CDS_SEC 1
J 0
(-900 550);
DISPLAY 1.021277 (-900 550);
DISPLAY INVISIBLE (-900 550);
FORCEPROP 1 LASTPIN (-750 500) $PN 1
J 0
(-738 512);
DISPLAY 0.808511 (-738 512);
PAINT WHITE (-738 512);
DISPLAY INVISIBLE (-738 512);
FORCEPROP 1 LASTPIN (-550 500) $PN 2
J 0
(-588 512);
DISPLAY 0.808511 (-588 512);
PAINT WHITE (-588 512);
DISPLAY INVISIBLE (-588 512);
FORCEADD OFFPAGE..3
R 2
(-350 2700);
FORCEPROP 2 LAST $XR0 20 
J 0
(-599 2700);
DISPLAY 0.638298 (-599 2700);
PAINT MONO (-599 2700);
FORCEPROP 2 LAST PATH I38
J 0
(-575 2750);
DISPLAY 1.021277 (-575 2750);
DISPLAY INVISIBLE (-575 2750);
FORCEPROP 1 LAST COMMENT_BODY TRUE
J 2
(-300 2600);
DISPLAY 0.872340 (-300 2600);
PAINT PEACH (-300 2600);
DISPLAY INVISIBLE (-300 2600);
FORCEPROP 1 LAST OFFPAGE TRUE
J 2
(-675 2575);
DISPLAY 0.872340 (-675 2575);
PAINT GREEN (-675 2575);
DISPLAY INVISIBLE (-675 2575);
FORCEPROP 2 LAST CDS_LIB standard
J 0
(-350 2700);
DISPLAY INVISIBLE (-350 2700);
FORCEADD Q_RES..1
(-650 450);
FORCEPROP 1 LAST MATERIAL CHIP
J 2
(-275 450);
DISPLAY 0.510638 (-275 450);
PAINT SKYBLUE (-275 450);
FORCEPROP 1 LAST VALUE 33.2
J 0
(-525 450);
DISPLAY 0.510638 (-525 450);
PAINT SKYBLUE (-525 450);
FORCEPROP 1 LAST PACK_TYPE 0402LF
J 0
(-400 300);
DISPLAY 0.510638 (-400 300);
PAINT SKYBLUE (-400 300);
DISPLAY INVISIBLE (-400 300);
FORCEPROP 1 LAST WATTAGE 1/16W
J 2
(-675 300);
DISPLAY 0.510638 (-675 300);
PAINT SKYBLUE (-675 300);
DISPLAY INVISIBLE (-675 300);
FORCEPROP 1 LAST PATH I380
J 0
(-700 600);
DISPLAY 0.978723 (-700 600);
PAINT WHITE (-700 600);
DISPLAY INVISIBLE (-700 600);
FORCEPROP 2 LAST CDS_LIB pure_quanta
J 0
(-650 450);
DISPLAY INVISIBLE (-650 450);
FORCEPROP 1 LAST PART_NUMBER CS03322FB03
J 0
(-700 550);
DISPLAY 0.510638 (-700 550);
PAINT WHITE (-700 550);
DISPLAY INVISIBLE (-700 550);
FORCEPROP 1 LAST TOLERANCE 1%
J 0
(-525 450);
DISPLAY 0.510638 (-525 450);
PAINT SKYBLUE (-525 450);
DISPLAY INVISIBLE (-525 450);
FORCEPROP 1 LAST LOCATION R150
J 2
(-825 450);
DISPLAY 0.702128 (-825 450);
PAINT YELLOW (-825 450);
FORCEPROP 1 LASTPIN (-750 450) $PN 1
J 0
(-738 462);
DISPLAY 0.808511 (-738 462);
PAINT WHITE (-738 462);
FORCEPROP 1 LASTPIN (-550 450) $PN 2
J 0
(-588 462);
DISPLAY 0.808511 (-588 462);
PAINT WHITE (-588 462);
FORCEPROP 0 LAST $SEC 1
J 0
(-550 500);
DISPLAY 0.680851 (-550 500);
PAINT MONO (-550 500);
DISPLAY INVISIBLE (-550 500);
FORCEPROP 0 LAST CDS_SEC 1
J 0
(-550 500);
DISPLAY 0.680851 (-550 500);
DISPLAY INVISIBLE (-550 500);
FORCEADD Q_RES..1
(-650 400);
FORCEPROP 1 LAST MATERIAL CHIP
J 2
(-275 400);
DISPLAY 0.510638 (-275 400);
PAINT SKYBLUE (-275 400);
FORCEPROP 1 LAST VALUE 33.2
J 0
(-525 400);
DISPLAY 0.510638 (-525 400);
PAINT SKYBLUE (-525 400);
FORCEPROP 1 LAST PACK_TYPE 0402LF
J 0
(-400 250);
DISPLAY 0.510638 (-400 250);
PAINT SKYBLUE (-400 250);
DISPLAY INVISIBLE (-400 250);
FORCEPROP 1 LAST WATTAGE 1/16W
J 2
(-675 250);
DISPLAY 0.510638 (-675 250);
PAINT SKYBLUE (-675 250);
DISPLAY INVISIBLE (-675 250);
FORCEPROP 1 LAST PATH I381
J 0
(-700 550);
DISPLAY 0.978723 (-700 550);
PAINT WHITE (-700 550);
DISPLAY INVISIBLE (-700 550);
FORCEPROP 2 LAST CDS_LIB pure_quanta
J 0
(-650 400);
DISPLAY INVISIBLE (-650 400);
FORCEPROP 1 LAST PART_NUMBER CS03322FB03
J 0
(-700 500);
DISPLAY 0.510638 (-700 500);
PAINT WHITE (-700 500);
DISPLAY INVISIBLE (-700 500);
FORCEPROP 1 LAST TOLERANCE 1%
J 0
(-525 400);
DISPLAY 0.510638 (-525 400);
PAINT SKYBLUE (-525 400);
DISPLAY INVISIBLE (-525 400);
FORCEPROP 1 LAST LOCATION R151
J 2
(-825 400);
DISPLAY 0.702128 (-825 400);
PAINT YELLOW (-825 400);
FORCEPROP 0 LAST $SEC 1
J 0
(-900 450);
DISPLAY 0.680851 (-900 450);
PAINT MONO (-900 450);
DISPLAY INVISIBLE (-900 450);
FORCEPROP 0 LAST CDS_SEC 1
J 0
(-900 450);
DISPLAY 1.021277 (-900 450);
DISPLAY INVISIBLE (-900 450);
FORCEPROP 1 LASTPIN (-750 400) $PN 1
J 0
(-738 412);
DISPLAY 0.808511 (-738 412);
PAINT WHITE (-738 412);
DISPLAY INVISIBLE (-738 412);
FORCEPROP 1 LASTPIN (-550 400) $PN 2
J 0
(-588 412);
DISPLAY 0.808511 (-588 412);
PAINT WHITE (-588 412);
DISPLAY INVISIBLE (-588 412);
FORCEADD Q_RES..1
(-650 350);
FORCEPROP 1 LAST VALUE 33.2
J 0
(-525 350);
DISPLAY 0.510638 (-525 350);
PAINT SKYBLUE (-525 350);
FORCEPROP 1 LAST MATERIAL CHIP
J 2
(-275 350);
DISPLAY 0.510638 (-275 350);
PAINT SKYBLUE (-275 350);
FORCEPROP 1 LAST PACK_TYPE 0402LF
J 0
(-400 200);
DISPLAY 0.510638 (-400 200);
PAINT SKYBLUE (-400 200);
DISPLAY INVISIBLE (-400 200);
FORCEPROP 1 LAST WATTAGE 1/16W
J 2
(-675 200);
DISPLAY 0.510638 (-675 200);
PAINT SKYBLUE (-675 200);
DISPLAY INVISIBLE (-675 200);
FORCEPROP 1 LAST PATH I382
J 0
(-700 500);
DISPLAY 0.978723 (-700 500);
PAINT WHITE (-700 500);
DISPLAY INVISIBLE (-700 500);
FORCEPROP 2 LAST CDS_LIB pure_quanta
J 0
(-650 350);
DISPLAY INVISIBLE (-650 350);
FORCEPROP 1 LAST PART_NUMBER CS03322FB03
J 0
(-700 450);
DISPLAY 0.510638 (-700 450);
PAINT WHITE (-700 450);
DISPLAY INVISIBLE (-700 450);
FORCEPROP 1 LAST TOLERANCE 1%
J 0
(-525 350);
DISPLAY 0.510638 (-525 350);
PAINT SKYBLUE (-525 350);
DISPLAY INVISIBLE (-525 350);
FORCEPROP 1 LAST LOCATION R433
J 2
(-825 350);
DISPLAY 0.702128 (-825 350);
PAINT YELLOW (-825 350);
FORCEPROP 1 LASTPIN (-750 350) $PN 1
J 0
(-738 362);
DISPLAY 0.808511 (-738 362);
PAINT WHITE (-738 362);
FORCEPROP 1 LASTPIN (-550 350) $PN 2
J 0
(-588 362);
DISPLAY 0.808511 (-588 362);
PAINT WHITE (-588 362);
FORCEPROP 0 LAST $SEC 1
J 0
(-550 400);
DISPLAY 0.680851 (-550 400);
PAINT MONO (-550 400);
DISPLAY INVISIBLE (-550 400);
FORCEPROP 0 LAST CDS_SEC 1
J 0
(-550 400);
DISPLAY 0.680851 (-550 400);
DISPLAY INVISIBLE (-550 400);
FORCEADD OFFPAGE..2
(5300 550);
FORCEPROP 2 LAST $XR1 10 
J 0
(5579 550);
DISPLAY 0.638298 (5579 550);
PAINT MONO (5579 550);
FORCEPROP 2 LAST $XR0 27 
J 0
(5489 550);
DISPLAY 0.638298 (5489 550);
PAINT MONO (5489 550);
FORCEPROP 2 LAST CDS_LIB standard
J 0
(5300 550);
DISPLAY INVISIBLE (5300 550);
FORCEPROP 2 LAST PATH I383
J 0
(5600 600);
DISPLAY 1.021277 (5600 600);
DISPLAY INVISIBLE (5600 600);
FORCEPROP 1 LAST OFFPAGE TRUE
J 0
(5625 425);
DISPLAY 0.872340 (5625 425);
PAINT GREEN (5625 425);
DISPLAY INVISIBLE (5625 425);
FORCEPROP 1 LAST COMMENT_BODY TRUE
J 0
(5255 455);
DISPLAY 0.872340 (5255 455);
PAINT PEACH (5255 455);
DISPLAY INVISIBLE (5255 455);
FORCEADD OFFPAGE..3
(5300 500);
FORCEPROP 2 LAST $XR1 27 
J 0
(5604 500);
DISPLAY 0.638298 (5604 500);
PAINT MONO (5604 500);
FORCEPROP 2 LAST $XR0 10 
J 0
(5514 500);
DISPLAY 0.638298 (5514 500);
PAINT MONO (5514 500);
FORCEPROP 2 LAST PATH I384
J 0
(5625 550);
DISPLAY 1.021277 (5625 550);
DISPLAY INVISIBLE (5625 550);
FORCEPROP 1 LAST COMMENT_BODY TRUE
J 0
(5250 400);
DISPLAY 0.872340 (5250 400);
PAINT PEACH (5250 400);
DISPLAY INVISIBLE (5250 400);
FORCEPROP 1 LAST OFFPAGE TRUE
J 0
(5625 375);
DISPLAY 0.872340 (5625 375);
PAINT GREEN (5625 375);
DISPLAY INVISIBLE (5625 375);
FORCEPROP 2 LAST CDS_LIB standard
J 0
(5300 500);
DISPLAY INVISIBLE (5300 500);
FORCEADD Q_RES..1
(4125 550);
FORCEPROP 1 LAST VALUE 33.2
J 0
(4250 550);
DISPLAY 0.510638 (4250 550);
PAINT SKYBLUE (4250 550);
FORCEPROP 1 LAST MATERIAL CHIP
J 2
(4500 550);
DISPLAY 0.510638 (4500 550);
PAINT SKYBLUE (4500 550);
FORCEPROP 1 LAST PACK_TYPE 0402LF
J 0
(4375 400);
DISPLAY 0.510638 (4375 400);
PAINT SKYBLUE (4375 400);
DISPLAY INVISIBLE (4375 400);
FORCEPROP 1 LAST WATTAGE 1/16W
J 2
(4100 400);
DISPLAY 0.510638 (4100 400);
PAINT SKYBLUE (4100 400);
DISPLAY INVISIBLE (4100 400);
FORCEPROP 1 LAST PATH I385
J 0
(4075 700);
DISPLAY 0.978723 (4075 700);
PAINT WHITE (4075 700);
DISPLAY INVISIBLE (4075 700);
FORCEPROP 2 LAST CDS_LIB pure_quanta
J 0
(4125 550);
DISPLAY INVISIBLE (4125 550);
FORCEPROP 1 LAST PART_NUMBER CS03322FB03
J 0
(4075 650);
DISPLAY 0.510638 (4075 650);
PAINT WHITE (4075 650);
DISPLAY INVISIBLE (4075 650);
FORCEPROP 1 LAST TOLERANCE 1%
J 0
(4250 550);
DISPLAY 0.510638 (4250 550);
PAINT SKYBLUE (4250 550);
DISPLAY INVISIBLE (4250 550);
FORCEPROP 1 LAST LOCATION R137
J 2
(3950 550);
DISPLAY 0.702128 (3950 550);
PAINT YELLOW (3950 550);
FORCEPROP 0 LAST $SEC 1
J 0
(3875 600);
DISPLAY 0.680851 (3875 600);
PAINT MONO (3875 600);
DISPLAY INVISIBLE (3875 600);
FORCEPROP 0 LAST CDS_SEC 1
J 0
(3875 600);
DISPLAY 1.021277 (3875 600);
DISPLAY INVISIBLE (3875 600);
FORCEPROP 1 LASTPIN (4025 550) $PN 1
J 0
(4037 562);
DISPLAY 0.808511 (4037 562);
PAINT WHITE (4037 562);
DISPLAY INVISIBLE (4037 562);
FORCEPROP 1 LASTPIN (4225 550) $PN 2
J 0
(4187 562);
DISPLAY 0.808511 (4187 562);
PAINT WHITE (4187 562);
DISPLAY INVISIBLE (4187 562);
FORCEADD Q_RES..1
(4125 500);
FORCEPROP 1 LAST VALUE 33.2
J 0
(4250 500);
DISPLAY 0.510638 (4250 500);
PAINT SKYBLUE (4250 500);
FORCEPROP 1 LAST MATERIAL CHIP
J 2
(4500 500);
DISPLAY 0.510638 (4500 500);
PAINT SKYBLUE (4500 500);
FORCEPROP 1 LAST PACK_TYPE 0402LF
J 0
(4375 350);
DISPLAY 0.510638 (4375 350);
PAINT SKYBLUE (4375 350);
DISPLAY INVISIBLE (4375 350);
FORCEPROP 1 LAST WATTAGE 1/16W
J 2
(4100 350);
DISPLAY 0.510638 (4100 350);
PAINT SKYBLUE (4100 350);
DISPLAY INVISIBLE (4100 350);
FORCEPROP 1 LAST PATH I386
J 0
(4075 650);
DISPLAY 0.978723 (4075 650);
PAINT WHITE (4075 650);
DISPLAY INVISIBLE (4075 650);
FORCEPROP 2 LAST CDS_LIB pure_quanta
J 0
(4125 500);
DISPLAY INVISIBLE (4125 500);
FORCEPROP 1 LAST PART_NUMBER CS03322FB03
J 0
(4075 600);
DISPLAY 0.510638 (4075 600);
PAINT WHITE (4075 600);
DISPLAY INVISIBLE (4075 600);
FORCEPROP 1 LAST TOLERANCE 1%
J 0
(4250 500);
DISPLAY 0.510638 (4250 500);
PAINT SKYBLUE (4250 500);
DISPLAY INVISIBLE (4250 500);
FORCEPROP 1 LAST LOCATION R144
J 2
(3950 500);
DISPLAY 0.702128 (3950 500);
PAINT YELLOW (3950 500);
FORCEPROP 1 LASTPIN (4025 500) $PN 1
J 0
(4037 512);
DISPLAY 0.808511 (4037 512);
PAINT WHITE (4037 512);
FORCEPROP 1 LASTPIN (4225 500) $PN 2
J 0
(4187 512);
DISPLAY 0.808511 (4187 512);
PAINT WHITE (4187 512);
FORCEPROP 0 LAST $SEC 1
J 0
(4225 550);
DISPLAY 0.680851 (4225 550);
PAINT MONO (4225 550);
DISPLAY INVISIBLE (4225 550);
FORCEPROP 0 LAST CDS_SEC 1
J 0
(4225 550);
DISPLAY 0.680851 (4225 550);
DISPLAY INVISIBLE (4225 550);
FORCEADD UNIVERSAL_GND..1
(2250 -525);
FORCEPROP 3 LASTPIN (2250 -475) SIG_NAME GND\g
J 0
(2260 -465);
DISPLAY 0.659574 (2260 -465);
PAINT MONO (2260 -465);
DISPLAY INVISIBLE (2260 -465);
FORCEPROP 2 LAST CDS_LIB logical_power
J 0
(2250 -525);
DISPLAY INVISIBLE (2250 -525);
FORCEPROP 1 LAST PATH I389
J 0
(2325 -525);
DISPLAY 0.872340 (2325 -525);
PAINT AQUA (2325 -525);
DISPLAY INVISIBLE (2325 -525);
FORCEPROP 1 LAST HDL_POWER GND
J 1
(2275 -600);
DISPLAY 0.702128 (2275 -600);
PAINT GREEN (2275 -600);
DISPLAY INVISIBLE (2275 -600);
FORCEADD OFFPAGE..3
R 2
(-350 2650);
FORCEPROP 2 LAST $XR0 20 
J 0
(-599 2650);
DISPLAY 0.638298 (-599 2650);
PAINT MONO (-599 2650);
FORCEPROP 2 LAST PATH I39
J 0
(-575 2700);
DISPLAY 1.021277 (-575 2700);
DISPLAY INVISIBLE (-575 2700);
FORCEPROP 1 LAST COMMENT_BODY TRUE
J 2
(-300 2550);
DISPLAY 0.872340 (-300 2550);
PAINT PEACH (-300 2550);
DISPLAY INVISIBLE (-300 2550);
FORCEPROP 1 LAST OFFPAGE TRUE
J 2
(-675 2525);
DISPLAY 0.872340 (-675 2525);
PAINT GREEN (-675 2525);
DISPLAY INVISIBLE (-675 2525);
FORCEPROP 2 LAST CDS_LIB standard
J 0
(-350 2650);
DISPLAY INVISIBLE (-350 2650);
FORCEADD Q_RES..1
R 2
(2550 -400);
FORCEPROP 1 LAST TOLERANCE 1%
J 2
(2500 -450);
DISPLAY 0.510638 (2500 -450);
PAINT SKYBLUE (2500 -450);
FORCEPROP 1 LAST MATERIAL EMPTY
J 2
(2975 -400);
DISPLAY 0.510638 (2975 -400);
PAINT RED (2975 -400);
FORCEPROP 1 LAST VALUE 100K
J 0
(2675 -400);
DISPLAY 0.510638 (2675 -400);
PAINT SKYBLUE (2675 -400);
FORCEPROP 1 LAST WATTAGE 1/16W
J 0
(2275 -450);
DISPLAY 0.510638 (2275 -450);
PAINT SKYBLUE (2275 -450);
FORCEPROP 1 LAST PACK_TYPE 0402LF
J 2
(2700 -450);
DISPLAY 0.510638 (2700 -450);
PAINT SKYBLUE (2700 -450);
FORCEPROP 1 LAST PART_NUMBER CS41002FB09
J 2
(2900 -500);
DISPLAY 0.510638 (2900 -500);
PAINT WHITE (2900 -500);
FORCEPROP 1 LAST PATH I390
J 2
(2600 -250);
DISPLAY 0.978723 (2600 -250);
PAINT WHITE (2600 -250);
DISPLAY INVISIBLE (2600 -250);
FORCEPROP 2 LAST SEC_TYPE 0402LF
J 0
(2600 -200);
DISPLAY 0.680851 (2600 -200);
DISPLAY INVISIBLE (2600 -200);
FORCEPROP 2 LAST CDS_LIB pure_quanta
J 2
(2550 -306);
DISPLAY INVISIBLE (2550 -306);
FORCEPROP 1 LAST LOCATION R820
J 2
(2425 -400);
DISPLAY 0.702128 (2425 -400);
PAINT YELLOW (2425 -400);
FORCEPROP 1 LASTPIN (2650 -400) $PN 1
J 0
(2615 -390);
DISPLAY 0.808511 (2615 -390);
PAINT WHITE (2615 -390);
FORCEPROP 1 LASTPIN (2450 -400) $PN 2
J 0
(2465 -390);
DISPLAY 0.808511 (2465 -390);
PAINT WHITE (2465 -390);
FORCEPROP 0 LAST SEC 1
J 0
(2650 -325);
DISPLAY 0.680851 (2650 -325);
PAINT MONO (2650 -325);
DISPLAY INVISIBLE (2650 -325);
FORCEADD Q_RES..1
R 2
(2550 -350);
FORCEPROP 1 LAST MATERIAL EMPTY
J 2
(2975 -350);
DISPLAY 0.510638 (2975 -350);
PAINT RED (2975 -350);
FORCEPROP 1 LAST VALUE 100K
J 0
(2675 -350);
DISPLAY 0.510638 (2675 -350);
PAINT SKYBLUE (2675 -350);
FORCEPROP 1 LAST PACK_TYPE 0402LF
J 2
(2750 -425);
DISPLAY 0.510638 (2750 -425);
PAINT SKYBLUE (2750 -425);
DISPLAY INVISIBLE (2750 -425);
FORCEPROP 1 LAST WATTAGE 1/16W
J 0
(2325 -425);
DISPLAY 0.510638 (2325 -425);
PAINT SKYBLUE (2325 -425);
DISPLAY INVISIBLE (2325 -425);
FORCEPROP 1 LAST PATH I391
J 2
(2600 -200);
DISPLAY 0.978723 (2600 -200);
PAINT WHITE (2600 -200);
DISPLAY INVISIBLE (2600 -200);
FORCEPROP 1 LAST PART_NUMBER CS41002FB09
J 2
(2500 -400);
DISPLAY 0.510638 (2500 -400);
PAINT WHITE (2500 -400);
DISPLAY INVISIBLE (2500 -400);
FORCEPROP 1 LAST TOLERANCE 1%
J 2
(2550 -425);
DISPLAY 0.510638 (2550 -425);
PAINT SKYBLUE (2550 -425);
DISPLAY INVISIBLE (2550 -425);
FORCEPROP 2 LAST SEC_TYPE 0402LF
J 0
(2600 -150);
DISPLAY 0.680851 (2600 -150);
DISPLAY INVISIBLE (2600 -150);
FORCEPROP 2 LAST CDS_LIB pure_quanta
J 2
(2550 -256);
DISPLAY INVISIBLE (2550 -256);
FORCEPROP 1 LAST LOCATION R819
J 2
(2425 -350);
DISPLAY 0.702128 (2425 -350);
PAINT YELLOW (2425 -350);
FORCEPROP 1 LASTPIN (2650 -350) $PN 1
J 0
(2615 -340);
DISPLAY 0.808511 (2615 -340);
PAINT WHITE (2615 -340);
FORCEPROP 1 LASTPIN (2450 -350) $PN 2
J 0
(2465 -340);
DISPLAY 0.808511 (2465 -340);
PAINT WHITE (2465 -340);
FORCEPROP 0 LAST SEC 1
J 0
(2650 -275);
DISPLAY 0.680851 (2650 -275);
PAINT MONO (2650 -275);
DISPLAY INVISIBLE (2650 -275);
FORCEADD Q_RES..1
R 2
(2550 -300);
FORCEPROP 1 LAST MATERIAL EMPTY
J 2
(2975 -300);
DISPLAY 0.510638 (2975 -300);
PAINT RED (2975 -300);
FORCEPROP 1 LAST VALUE 100K
J 0
(2675 -300);
DISPLAY 0.510638 (2675 -300);
PAINT SKYBLUE (2675 -300);
FORCEPROP 1 LAST PACK_TYPE 0402LF
J 2
(2750 -375);
DISPLAY 0.510638 (2750 -375);
PAINT SKYBLUE (2750 -375);
DISPLAY INVISIBLE (2750 -375);
FORCEPROP 1 LAST WATTAGE 1/16W
J 0
(2325 -375);
DISPLAY 0.510638 (2325 -375);
PAINT SKYBLUE (2325 -375);
DISPLAY INVISIBLE (2325 -375);
FORCEPROP 1 LAST PATH I392
J 2
(2600 -150);
DISPLAY 0.978723 (2600 -150);
PAINT WHITE (2600 -150);
DISPLAY INVISIBLE (2600 -150);
FORCEPROP 1 LAST PART_NUMBER CS41002FB09
J 2
(2500 -350);
DISPLAY 0.510638 (2500 -350);
PAINT WHITE (2500 -350);
DISPLAY INVISIBLE (2500 -350);
FORCEPROP 1 LAST TOLERANCE 1%
J 2
(2550 -375);
DISPLAY 0.510638 (2550 -375);
PAINT SKYBLUE (2550 -375);
DISPLAY INVISIBLE (2550 -375);
FORCEPROP 2 LAST SEC_TYPE 0402LF
J 0
(2600 -100);
DISPLAY 0.680851 (2600 -100);
DISPLAY INVISIBLE (2600 -100);
FORCEPROP 2 LAST CDS_LIB pure_quanta
J 2
(2550 -206);
DISPLAY INVISIBLE (2550 -206);
FORCEPROP 1 LAST LOCATION R818
J 2
(2425 -300);
DISPLAY 0.702128 (2425 -300);
PAINT YELLOW (2425 -300);
FORCEPROP 1 LASTPIN (2650 -300) $PN 1
J 0
(2615 -290);
DISPLAY 0.808511 (2615 -290);
PAINT WHITE (2615 -290);
FORCEPROP 1 LASTPIN (2450 -300) $PN 2
J 0
(2465 -290);
DISPLAY 0.808511 (2465 -290);
PAINT WHITE (2465 -290);
FORCEPROP 0 LAST SEC 1
J 0
(2650 -225);
DISPLAY 0.680851 (2650 -225);
PAINT MONO (2650 -225);
DISPLAY INVISIBLE (2650 -225);
FORCEADD Q_RES..1
R 2
(2550 -250);
FORCEPROP 1 LAST VALUE 100K
J 0
(2675 -250);
DISPLAY 0.510638 (2675 -250);
PAINT SKYBLUE (2675 -250);
FORCEPROP 1 LAST MATERIAL EMPTY
J 2
(2975 -250);
DISPLAY 0.510638 (2975 -250);
PAINT RED (2975 -250);
FORCEPROP 1 LAST PACK_TYPE 0402LF
J 2
(2750 -325);
DISPLAY 0.510638 (2750 -325);
PAINT SKYBLUE (2750 -325);
DISPLAY INVISIBLE (2750 -325);
FORCEPROP 1 LAST WATTAGE 1/16W
J 0
(2325 -325);
DISPLAY 0.510638 (2325 -325);
PAINT SKYBLUE (2325 -325);
DISPLAY INVISIBLE (2325 -325);
FORCEPROP 1 LAST PATH I393
J 2
(2600 -100);
DISPLAY 0.978723 (2600 -100);
PAINT WHITE (2600 -100);
DISPLAY INVISIBLE (2600 -100);
FORCEPROP 1 LAST PART_NUMBER CS41002FB09
J 2
(2500 -300);
DISPLAY 0.510638 (2500 -300);
PAINT WHITE (2500 -300);
DISPLAY INVISIBLE (2500 -300);
FORCEPROP 1 LAST TOLERANCE 1%
J 2
(2550 -325);
DISPLAY 0.510638 (2550 -325);
PAINT SKYBLUE (2550 -325);
DISPLAY INVISIBLE (2550 -325);
FORCEPROP 2 LAST SEC_TYPE 0402LF
J 0
(2600 -50);
DISPLAY 0.680851 (2600 -50);
DISPLAY INVISIBLE (2600 -50);
FORCEPROP 2 LAST CDS_LIB pure_quanta
J 2
(2550 -156);
DISPLAY INVISIBLE (2550 -156);
FORCEPROP 1 LAST LOCATION R817
J 2
(2425 -250);
DISPLAY 0.702128 (2425 -250);
PAINT YELLOW (2425 -250);
FORCEPROP 1 LASTPIN (2650 -250) $PN 1
J 0
(2615 -240);
DISPLAY 0.808511 (2615 -240);
PAINT WHITE (2615 -240);
FORCEPROP 1 LASTPIN (2450 -250) $PN 2
J 0
(2465 -240);
DISPLAY 0.808511 (2465 -240);
PAINT WHITE (2465 -240);
FORCEPROP 0 LAST SEC 1
J 0
(2650 -175);
DISPLAY 0.680851 (2650 -175);
PAINT MONO (2650 -175);
DISPLAY INVISIBLE (2650 -175);
FORCEADD OFFPAGE..4
(5875 -50);
FORCEPROP 2 LAST $XR0 12 
J 0
(6061 -50);
DISPLAY 0.638298 (6061 -50);
PAINT MONO (6061 -50);
FORCEPROP 2 LAST $XR1 34 
J 0
(6151 -50);
DISPLAY 0.638298 (6151 -50);
PAINT MONO (6151 -50);
FORCEPROP 2 LAST PATH I397
J 0
(6250 0);
DISPLAY 1.021277 (6250 0);
DISPLAY INVISIBLE (6250 0);
FORCEPROP 1 LAST COMMENT_BODY TRUE
J 0
(5850 -150);
DISPLAY 0.872340 (5850 -150);
PAINT PEACH (5850 -150);
DISPLAY INVISIBLE (5850 -150);
FORCEPROP 1 LAST OFFPAGE TRUE
J 0
(6200 -175);
DISPLAY 0.872340 (6200 -175);
PAINT GREEN (6200 -175);
DISPLAY INVISIBLE (6200 -175);
FORCEPROP 2 LAST CDS_LIB standard
J 0
(5875 -50);
DISPLAY INVISIBLE (5875 -50);
FORCEADD Q_RES..1
(-1475 -325);
FORCEPROP 1 LAST VALUE 4.7K
J 2
(-1600 -325);
DISPLAY 0.510638 (-1600 -325);
PAINT SKYBLUE (-1600 -325);
FORCEPROP 1 LAST MATERIAL EMPTY
J 0
(-1350 -325);
DISPLAY 0.510638 (-1350 -325);
PAINT RED (-1350 -325);
FORCEPROP 1 LAST PART_NUMBER CS24702FB06
J 0
(-1525 -225);
DISPLAY 0.510638 (-1525 -225);
PAINT WHITE (-1525 -225);
DISPLAY INVISIBLE (-1525 -225);
FORCEPROP 2 LAST CDS_LIB pure_quanta
J 0
(-1475 -325);
DISPLAY INVISIBLE (-1475 -325);
FORCEPROP 1 LAST TOLERANCE 1%
J 0
(-1475 -425);
DISPLAY 0.510638 (-1475 -425);
PAINT SKYBLUE (-1475 -425);
DISPLAY INVISIBLE (-1475 -425);
FORCEPROP 1 LAST PATH I4
J 0
(-1525 -175);
DISPLAY 0.978723 (-1525 -175);
PAINT WHITE (-1525 -175);
DISPLAY INVISIBLE (-1525 -175);
FORCEPROP 1 LAST WATTAGE 1/16W
J 2
(-1500 -475);
DISPLAY 0.510638 (-1500 -475);
PAINT SKYBLUE (-1500 -475);
DISPLAY INVISIBLE (-1500 -475);
FORCEPROP 1 LAST PACK_TYPE 0402LF
J 0
(-1225 -475);
DISPLAY 0.510638 (-1225 -475);
PAINT SKYBLUE (-1225 -475);
DISPLAY INVISIBLE (-1225 -475);
FORCEPROP 1 LAST LOCATION R115
J 0
(-1825 -325);
DISPLAY 0.702128 (-1825 -325);
PAINT YELLOW (-1825 -325);
FORCEPROP 0 LAST $SEC 1
J 0
(-1825 -275);
DISPLAY INVISIBLE (-1825 -275);
FORCEPROP 0 LAST CDS_SEC 1
J 0
(-1825 -275);
DISPLAY INVISIBLE (-1825 -275);
FORCEPROP 1 LASTPIN (-1575 -325) $PN 1
J 0
(-1563 -313);
DISPLAY 0.808511 (-1563 -313);
PAINT WHITE (-1563 -313);
DISPLAY INVISIBLE (-1563 -313);
FORCEPROP 1 LASTPIN (-1375 -325) $PN 2
J 0
(-1413 -313);
DISPLAY 0.808511 (-1413 -313);
PAINT WHITE (-1413 -313);
DISPLAY INVISIBLE (-1413 -313);
FORCEADD OFFPAGE..3
R 2
(-350 2750);
FORCEPROP 2 LAST $XR0 20 
J 0
(-599 2750);
DISPLAY 0.638298 (-599 2750);
PAINT MONO (-599 2750);
FORCEPROP 2 LAST PATH I40
J 0
(-575 2800);
DISPLAY 1.021277 (-575 2800);
DISPLAY INVISIBLE (-575 2800);
FORCEPROP 1 LAST COMMENT_BODY TRUE
J 2
(-300 2650);
DISPLAY 0.872340 (-300 2650);
PAINT PEACH (-300 2650);
DISPLAY INVISIBLE (-300 2650);
FORCEPROP 1 LAST OFFPAGE TRUE
J 2
(-675 2625);
DISPLAY 0.872340 (-675 2625);
PAINT GREEN (-675 2625);
DISPLAY INVISIBLE (-675 2625);
FORCEPROP 2 LAST CDS_LIB standard
J 0
(-350 2750);
DISPLAY INVISIBLE (-350 2750);
FORCEADD OFFPAGE..4
(5875 -350);
FORCEPROP 2 LAST $XR0 10 
J 0
(6061 -350);
DISPLAY 0.638298 (6061 -350);
PAINT MONO (6061 -350);
FORCEPROP 2 LAST CDS_LIB standard
J 0
(5875 -350);
DISPLAY INVISIBLE (5875 -350);
FORCEPROP 1 LAST OFFPAGE TRUE
J 0
(6200 -475);
DISPLAY 0.872340 (6200 -475);
PAINT GREEN (6200 -475);
DISPLAY INVISIBLE (6200 -475);
FORCEPROP 1 LAST COMMENT_BODY TRUE
J 0
(5850 -450);
DISPLAY 0.872340 (5850 -450);
PAINT PEACH (5850 -450);
DISPLAY INVISIBLE (5850 -450);
FORCEPROP 2 LAST PATH I400
J 0
(6175 -300);
DISPLAY 0.680851 (6175 -300);
DISPLAY INVISIBLE (6175 -300);
FORCEADD OFFPAGE..2
R 2
(-350 2500);
FORCEPROP 2 LAST $XR0 20 
J 0
(-574 2500);
DISPLAY 0.638298 (-574 2500);
PAINT MONO (-574 2500);
FORCEPROP 2 LAST PATH I41
J 0
(-550 2550);
DISPLAY 1.021277 (-550 2550);
DISPLAY INVISIBLE (-550 2550);
FORCEPROP 1 LAST COMMENT_BODY TRUE
J 2
(-305 2405);
DISPLAY 0.872340 (-305 2405);
PAINT PEACH (-305 2405);
DISPLAY INVISIBLE (-305 2405);
FORCEPROP 1 LAST OFFPAGE TRUE
J 2
(-675 2375);
DISPLAY 0.872340 (-675 2375);
PAINT GREEN (-675 2375);
DISPLAY INVISIBLE (-675 2375);
FORCEPROP 2 LAST CDS_LIB standard
J 0
(-350 2500);
DISPLAY INVISIBLE (-350 2500);
FORCEADD OFFPAGE..2
(5875 100);
FORCEPROP 2 LAST $XR1 27 
J 0
(6154 100);
DISPLAY 0.638298 (6154 100);
PAINT MONO (6154 100);
FORCEPROP 2 LAST $XR0 10 
J 0
(6064 100);
DISPLAY 0.638298 (6064 100);
PAINT MONO (6064 100);
FORCEPROP 2 LAST PATH I410
J 0
(6250 150);
DISPLAY 0.680851 (6250 150);
DISPLAY INVISIBLE (6250 150);
FORCEPROP 1 LAST COMMENT_BODY TRUE
J 0
(5830 5);
DISPLAY 0.872340 (5830 5);
PAINT PEACH (5830 5);
DISPLAY INVISIBLE (5830 5);
FORCEPROP 1 LAST OFFPAGE TRUE
J 0
(6200 -25);
DISPLAY 0.872340 (6200 -25);
PAINT GREEN (6200 -25);
DISPLAY INVISIBLE (6200 -25);
FORCEPROP 2 LAST CDS_LIB standard
J 0
(5875 100);
DISPLAY INVISIBLE (5875 100);
FORCEADD OFFPAGE..2
(-200 -425);
FORCEPROP 2 LAST $XR0 10 
J 0
(-11 -425);
DISPLAY 0.638298 (-11 -425);
PAINT MONO (-11 -425);
FORCEPROP 2 LAST $XR1 12 
J 0
(79 -425);
DISPLAY 0.638298 (79 -425);
PAINT MONO (79 -425);
FORCEPROP 2 LAST PATH I42
J 0
(50 -375);
DISPLAY 1.021277 (50 -375);
DISPLAY INVISIBLE (50 -375);
FORCEPROP 1 LAST COMMENT_BODY TRUE
J 0
(-245 -520);
DISPLAY 0.872340 (-245 -520);
PAINT PEACH (-245 -520);
DISPLAY INVISIBLE (-245 -520);
FORCEPROP 1 LAST OFFPAGE TRUE
J 0
(125 -550);
DISPLAY 0.872340 (125 -550);
PAINT GREEN (125 -550);
DISPLAY INVISIBLE (125 -550);
FORCEPROP 2 LAST CDS_LIB standard
J 0
(-200 -425);
DISPLAY INVISIBLE (-200 -425);
FORCEADD Q_CAP..2
(3825 4150);
FORCEPROP 1 LAST VALUE 0.1UF
J 2
(4125 4150);
DISPLAY 0.510638 (4125 4150);
PAINT SKYBLUE (4125 4150);
FORCEPROP 2 LAST CDS_LIB pure_quanta
J 0
(3825 4150);
DISPLAY INVISIBLE (3825 4150);
FORCEPROP 1 LAST PATH I428
J 0
(3825 4350);
DISPLAY 0.978723 (3825 4350);
PAINT WHITE (3825 4350);
DISPLAY INVISIBLE (3825 4350);
FORCEPROP 1 LAST PACK_TYPE 0402
J 1
(3825 3950);
DISPLAY 0.510638 (3825 3950);
PAINT SKYBLUE (3825 3950);
DISPLAY INVISIBLE (3825 3950);
FORCEPROP 1 LAST VOLTAGE 25V
J 0
(3825 4050);
DISPLAY 0.510638 (3825 4050);
PAINT SKYBLUE (3825 4050);
DISPLAY INVISIBLE (3825 4050);
FORCEPROP 1 LAST TOLERANCE 10%
J 2
(3825 4000);
DISPLAY 0.510638 (3825 4000);
PAINT SKYBLUE (3825 4000);
DISPLAY INVISIBLE (3825 4000);
FORCEPROP 1 LAST PART_NUMBER CH4104K1B00
J 1
(4025 4225);
DISPLAY 0.510638 (4025 4225);
PAINT WHITE (4025 4225);
DISPLAY INVISIBLE (4025 4225);
FORCEPROP 1 LAST MATERIAL X7R
J 0
(3825 4000);
DISPLAY 0.510638 (3825 4000);
PAINT SKYBLUE (3825 4000);
DISPLAY INVISIBLE (3825 4000);
FORCEPROP 1 LAST $LOCATION C272
J 1
(3675 4150);
DISPLAY 0.702128 (3675 4150);
PAINT YELLOW (3675 4150);
FORCEPROP 1 LASTPIN (3725 4150) $PN 1
J 0
(3715 4165);
DISPLAY 0.787234 (3715 4165);
PAINT MONO (3715 4165);
FORCEPROP 1 LASTPIN (3925 4150) $PN 2
J 0
(3910 4165);
DISPLAY 0.787234 (3910 4165);
PAINT MONO (3910 4165);
FORCEPROP 0 LAST CDS_LOCATION C272
J 0
(3675 4200);
DISPLAY 0.680851 (3675 4200);
DISPLAY INVISIBLE (3675 4200);
FORCEPROP 0 LAST $SEC 1
J 0
(3675 4200);
DISPLAY 0.680851 (3675 4200);
PAINT MONO (3675 4200);
DISPLAY INVISIBLE (3675 4200);
FORCEPROP 0 LAST CDS_SEC 1
J 0
(3675 4200);
DISPLAY 0.680851 (3675 4200);
DISPLAY INVISIBLE (3675 4200);
FORCEADD Q_CAP..2
(3825 4200);
FORCEPROP 1 LAST PART_NUMBER CH4104K1B00
J 1
(4150 4325);
DISPLAY 0.510638 (4150 4325);
PAINT WHITE (4150 4325);
FORCEPROP 1 LAST PACK_TYPE 0402
J 1
(4025 4275);
DISPLAY 0.510638 (4025 4275);
PAINT SKYBLUE (4025 4275);
FORCEPROP 1 LAST MATERIAL X7R
J 0
(4100 4275);
DISPLAY 0.510638 (4100 4275);
PAINT SKYBLUE (4100 4275);
FORCEPROP 1 LAST VALUE 0.1UF
J 2
(4125 4200);
DISPLAY 0.510638 (4125 4200);
PAINT SKYBLUE (4125 4200);
FORCEPROP 1 LAST TOLERANCE 10%
J 2
(4425 4275);
DISPLAY 0.510638 (4425 4275);
PAINT SKYBLUE (4425 4275);
FORCEPROP 1 LAST VOLTAGE 25V
J 0
(4225 4275);
DISPLAY 0.510638 (4225 4275);
PAINT SKYBLUE (4225 4275);
FORCEPROP 1 LAST PATH I429
J 0
(3825 4400);
DISPLAY 0.978723 (3825 4400);
PAINT WHITE (3825 4400);
DISPLAY INVISIBLE (3825 4400);
FORCEPROP 2 LAST CDS_LIB pure_quanta
J 0
(3825 4200);
DISPLAY INVISIBLE (3825 4200);
FORCEPROP 1 LAST $LOCATION C271
J 1
(3675 4200);
DISPLAY 0.702128 (3675 4200);
PAINT YELLOW (3675 4200);
FORCEPROP 1 LASTPIN (3725 4200) $PN 1
J 0
(3715 4215);
DISPLAY 0.787234 (3715 4215);
PAINT MONO (3715 4215);
FORCEPROP 1 LASTPIN (3925 4200) $PN 2
J 0
(3910 4215);
DISPLAY 0.787234 (3910 4215);
PAINT MONO (3910 4215);
FORCEPROP 0 LAST CDS_LOCATION C271
J 0
(4150 4350);
DISPLAY 0.680851 (4150 4350);
DISPLAY INVISIBLE (4150 4350);
FORCEPROP 0 LAST $SEC 1
J 0
(4150 4350);
DISPLAY 0.680851 (4150 4350);
PAINT MONO (4150 4350);
DISPLAY INVISIBLE (4150 4350);
FORCEPROP 0 LAST CDS_SEC 1
J 0
(4150 4350);
DISPLAY 0.680851 (4150 4350);
DISPLAY INVISIBLE (4150 4350);
FORCEADD OFFPAGE..2
(-200 -375);
FORCEPROP 2 LAST $XR0 10 
J 0
(-11 -375);
DISPLAY 0.638298 (-11 -375);
PAINT MONO (-11 -375);
FORCEPROP 2 LAST $XR1 12 
J 0
(79 -375);
DISPLAY 0.638298 (79 -375);
PAINT MONO (79 -375);
FORCEPROP 2 LAST PATH I43
J 0
(50 -325);
DISPLAY 1.021277 (50 -325);
DISPLAY INVISIBLE (50 -325);
FORCEPROP 1 LAST COMMENT_BODY TRUE
J 0
(-245 -470);
DISPLAY 0.872340 (-245 -470);
PAINT PEACH (-245 -470);
DISPLAY INVISIBLE (-245 -470);
FORCEPROP 1 LAST OFFPAGE TRUE
J 0
(125 -500);
DISPLAY 0.872340 (125 -500);
PAINT GREEN (125 -500);
DISPLAY INVISIBLE (125 -500);
FORCEPROP 2 LAST CDS_LIB standard
J 0
(-200 -375);
DISPLAY INVISIBLE (-200 -375);
FORCEADD OFFPAGE..2
(4800 4200);
FORCEPROP 2 LAST $XR0 10 
J 0
(4989 4200);
DISPLAY 0.638298 (4989 4200);
PAINT MONO (4989 4200);
FORCEPROP 1 LAST COMMENT_BODY TRUE
J 0
(4755 4105);
DISPLAY 0.872340 (4755 4105);
PAINT PEACH (4755 4105);
DISPLAY INVISIBLE (4755 4105);
FORCEPROP 1 LAST OFFPAGE TRUE
J 0
(5125 4075);
DISPLAY 0.872340 (5125 4075);
PAINT GREEN (5125 4075);
DISPLAY INVISIBLE (5125 4075);
FORCEPROP 2 LAST PATH I430
J 0
(4975 4275);
DISPLAY 0.680851 (4975 4275);
DISPLAY INVISIBLE (4975 4275);
FORCEPROP 2 LAST CDS_LIB standard
J 0
(4800 4200);
DISPLAY INVISIBLE (4800 4200);
FORCEADD OFFPAGE..2
(4800 4150);
FORCEPROP 2 LAST $XR0 10 
J 0
(4989 4150);
DISPLAY 0.638298 (4989 4150);
PAINT MONO (4989 4150);
FORCEPROP 1 LAST COMMENT_BODY TRUE
J 0
(4755 4055);
DISPLAY 0.872340 (4755 4055);
PAINT PEACH (4755 4055);
DISPLAY INVISIBLE (4755 4055);
FORCEPROP 1 LAST OFFPAGE TRUE
J 0
(5125 4025);
DISPLAY 0.872340 (5125 4025);
PAINT GREEN (5125 4025);
DISPLAY INVISIBLE (5125 4025);
FORCEPROP 2 LAST PATH I431
J 0
(4975 4225);
DISPLAY 0.680851 (4975 4225);
DISPLAY INVISIBLE (4975 4225);
FORCEPROP 2 LAST CDS_LIB standard
J 0
(4800 4150);
DISPLAY INVISIBLE (4800 4150);
FORCEADD OFFPAGE..1
(-425 4000);
FORCEPROP 2 LAST $XR0 10 
J 0
(-646 4000);
DISPLAY 0.638298 (-646 4000);
PAINT MONO (-646 4000);
FORCEPROP 1 LAST COMMENT_BODY TRUE
J 0
(-300 3900);
DISPLAY 0.872340 (-300 3900);
PAINT PEACH (-300 3900);
DISPLAY INVISIBLE (-300 3900);
FORCEPROP 1 LAST OFFPAGE TRUE
J 0
(-100 3875);
DISPLAY 0.872340 (-100 3875);
PAINT GREEN (-100 3875);
DISPLAY INVISIBLE (-100 3875);
FORCEPROP 2 LAST PATH I432
J 0
(-375 4075);
DISPLAY 0.680851 (-375 4075);
DISPLAY INVISIBLE (-375 4075);
FORCEPROP 2 LAST CDS_LIB standard
J 0
(-425 4000);
DISPLAY INVISIBLE (-425 4000);
FORCEADD OFFPAGE..1
(-425 4050);
FORCEPROP 2 LAST $XR0 10 
J 0
(-646 4050);
DISPLAY 0.638298 (-646 4050);
PAINT MONO (-646 4050);
FORCEPROP 1 LAST COMMENT_BODY TRUE
J 0
(-300 3950);
DISPLAY 0.872340 (-300 3950);
PAINT PEACH (-300 3950);
DISPLAY INVISIBLE (-300 3950);
FORCEPROP 1 LAST OFFPAGE TRUE
J 0
(-100 3925);
DISPLAY 0.872340 (-100 3925);
PAINT GREEN (-100 3925);
DISPLAY INVISIBLE (-100 3925);
FORCEPROP 2 LAST PATH I433
J 0
(-375 4125);
DISPLAY 0.680851 (-375 4125);
DISPLAY INVISIBLE (-375 4125);
FORCEPROP 2 LAST CDS_LIB standard
J 0
(-425 4050);
DISPLAY INVISIBLE (-425 4050);
FORCEADD OFFPAGE..1
(-425 4150);
FORCEPROP 2 LAST $XR0 10 
J 0
(-646 4150);
DISPLAY 0.638298 (-646 4150);
PAINT MONO (-646 4150);
FORCEPROP 2 LAST CDS_LIB standard
J 0
(-425 4150);
DISPLAY INVISIBLE (-425 4150);
FORCEPROP 2 LAST PATH I434
J 0
(-375 4225);
DISPLAY 0.680851 (-375 4225);
DISPLAY INVISIBLE (-375 4225);
FORCEPROP 1 LAST COMMENT_BODY TRUE
J 0
(-300 4050);
DISPLAY 0.872340 (-300 4050);
PAINT PEACH (-300 4050);
DISPLAY INVISIBLE (-300 4050);
FORCEPROP 1 LAST OFFPAGE TRUE
J 0
(-100 4025);
DISPLAY 0.872340 (-100 4025);
PAINT GREEN (-100 4025);
DISPLAY INVISIBLE (-100 4025);
FORCEADD OFFPAGE..1
(-425 4200);
FORCEPROP 2 LAST $XR0 10 
J 0
(-646 4200);
DISPLAY 0.638298 (-646 4200);
PAINT MONO (-646 4200);
FORCEPROP 2 LAST CDS_LIB standard
J 0
(-425 4200);
DISPLAY INVISIBLE (-425 4200);
FORCEPROP 2 LAST PATH I435
J 0
(-375 4275);
DISPLAY 0.680851 (-375 4275);
DISPLAY INVISIBLE (-375 4275);
FORCEPROP 1 LAST COMMENT_BODY TRUE
J 0
(-300 4100);
DISPLAY 0.872340 (-300 4100);
PAINT PEACH (-300 4100);
DISPLAY INVISIBLE (-300 4100);
FORCEPROP 1 LAST OFFPAGE TRUE
J 0
(-100 4075);
DISPLAY 0.872340 (-100 4075);
PAINT GREEN (-100 4075);
DISPLAY INVISIBLE (-100 4075);
FORCEADD AST2600A3GP..1
(1825 2250);
FORCEPROP 1 LAST MATERIAL IC
J 0
(932 4666);
DISPLAY 0.723404 (932 4666);
FORCEPROP 2 LAST VALUE AST2600A3-GP
J 0
(950 4975);
DISPLAY 0.680851 (950 4975);
FORCEPROP 2 LAST PART_TYPE SMLF
J 0
(950 5025);
DISPLAY 0.680851 (950 5025);
FORCEPROP 1 LAST PART_NUMBER AJ026000T06
J 0
(932 4793);
DISPLAY 0.723404 (932 4793);
FORCEPROP 1 LAST NEEDS_NO_SIZE TRUE
J 0
(1825 2250);
DISPLAY 0.723404 (1825 2250);
DISPLAY INVISIBLE (1825 2250);
FORCEPROP 1 LAST CDS_LMAN_SYM_OUTLINE -900,2400,900,-2400
J 0
(1825 2250);
DISPLAY 0.468085 (1825 2250);
PAINT GREEN (1825 2250);
DISPLAY INVISIBLE (1825 2250);
FORCEPROP 1 LAST PATH I436
J 0
(1825 2250);
DISPLAY 0.723404 (1825 2250);
DISPLAY INVISIBLE (1825 2250);
FORCEPROP 2 LAST CDS_LIB pure_quanta
J 0
(1825 2250);
DISPLAY INVISIBLE (1825 2250);
FORCEPROP 1 LAST LOCATION U5
J 0
(932 4940);
DISPLAY 0.723404 (932 4940);
FORCEPROP 0 LASTPIN (775 3850) $PN AB3
J 2
(765 3860);
DISPLAY 0.680851 (765 3860);
PAINT MONO (765 3860);
FORCEPROP 0 LASTPIN (775 3900) $PN AC3
J 2
(765 3910);
DISPLAY 0.680851 (765 3910);
PAINT MONO (765 3910);
FORCEPROP 0 LASTPIN (775 3700) $PN C7
J 2
(765 3710);
DISPLAY 0.680851 (765 3710);
PAINT MONO (765 3710);
FORCEPROP 0 LASTPIN (2875 3850) $PN AB1
J 0
(2885 3860);
DISPLAY 0.680851 (2885 3860);
PAINT MONO (2885 3860);
FORCEPROP 0 LASTPIN (2875 3700) $PN AA2
J 0
(2885 3710);
DISPLAY 0.680851 (2885 3710);
PAINT MONO (2885 3710);
FORCEPROP 0 LASTPIN (2875 3900) $PN AC1
J 0
(2885 3910);
DISPLAY 0.680851 (2885 3910);
PAINT MONO (2885 3910);
FORCEPROP 0 LASTPIN (2875 3750) $PN AB2
J 0
(2885 3760);
DISPLAY 0.680851 (2885 3760);
PAINT MONO (2885 3760);
FORCEPROP 0 LASTPIN (2875 650) $PN M24
J 0
(2885 660);
DISPLAY 0.680851 (2885 660);
PAINT MONO (2885 660);
FORCEPROP 0 LASTPIN (2875 600) $PN M25
J 0
(2885 610);
DISPLAY 0.680851 (2885 610);
PAINT MONO (2885 610);
FORCEPROP 0 LASTPIN (2875 550) $PN L26
J 0
(2885 560);
DISPLAY 0.680851 (2885 560);
PAINT MONO (2885 560);
FORCEPROP 0 LASTPIN (2875 500) $PN K24
J 0
(2885 510);
DISPLAY 0.680851 (2885 510);
PAINT MONO (2885 510);
FORCEPROP 0 LASTPIN (2875 250) $PN K26
J 0
(2885 260);
DISPLAY 0.680851 (2885 260);
PAINT MONO (2885 260);
FORCEPROP 0 LASTPIN (2875 200) $PN L24
J 0
(2885 210);
DISPLAY 0.680851 (2885 210);
PAINT MONO (2885 210);
FORCEPROP 0 LASTPIN (2875 150) $PN L23
J 0
(2885 160);
DISPLAY 0.680851 (2885 160);
PAINT MONO (2885 160);
FORCEPROP 0 LASTPIN (2875 100) $PN K25
J 0
(2885 110);
DISPLAY 0.680851 (2885 110);
PAINT MONO (2885 110);
FORCEPROP 0 LASTPIN (775 1750) $PN D22
J 2
(765 1760);
DISPLAY 0.680851 (765 1760);
PAINT MONO (765 1760);
FORCEPROP 0 LASTPIN (775 1700) $PN E22
J 2
(765 1710);
DISPLAY 0.680851 (765 1710);
PAINT MONO (765 1710);
FORCEPROP 0 LASTPIN (775 1650) $PN D23
J 2
(765 1660);
DISPLAY 0.680851 (765 1660);
PAINT MONO (765 1660);
FORCEPROP 0 LASTPIN (775 1600) $PN C23
J 2
(765 1610);
DISPLAY 0.680851 (765 1610);
PAINT MONO (765 1610);
FORCEPROP 0 LASTPIN (775 1550) $PN C22
J 2
(765 1560);
DISPLAY 0.680851 (765 1560);
PAINT MONO (765 1560);
FORCEPROP 0 LASTPIN (775 1500) $PN A25
J 2
(765 1510);
DISPLAY 0.680851 (765 1510);
PAINT MONO (765 1510);
FORCEPROP 0 LASTPIN (775 1450) $PN A24
J 2
(765 1460);
DISPLAY 0.680851 (765 1460);
PAINT MONO (765 1460);
FORCEPROP 0 LASTPIN (775 1400) $PN A23
J 2
(765 1410);
DISPLAY 0.680851 (765 1410);
PAINT MONO (765 1410);
FORCEPROP 0 LASTPIN (775 1100) $PN E21
J 2
(765 1110);
DISPLAY 0.680851 (765 1110);
PAINT MONO (765 1110);
FORCEPROP 0 LASTPIN (775 1050) $PN B22
J 2
(765 1060);
DISPLAY 0.680851 (765 1060);
PAINT MONO (765 1060);
FORCEPROP 0 LASTPIN (775 1000) $PN C21
J 2
(765 1010);
DISPLAY 0.680851 (765 1010);
PAINT MONO (765 1010);
FORCEPROP 0 LASTPIN (775 950) $PN A22
J 2
(765 960);
DISPLAY 0.680851 (765 960);
PAINT MONO (765 960);
FORCEPROP 0 LASTPIN (775 900) $PN A21
J 2
(765 910);
DISPLAY 0.680851 (765 910);
PAINT MONO (765 910);
FORCEPROP 0 LASTPIN (775 850) $PN E20
J 2
(765 860);
DISPLAY 0.680851 (765 860);
PAINT MONO (765 860);
FORCEPROP 0 LASTPIN (775 800) $PN D21
J 2
(765 810);
DISPLAY 0.680851 (765 810);
PAINT MONO (765 810);
FORCEPROP 0 LASTPIN (775 750) $PN B21
J 2
(765 760);
DISPLAY 0.680851 (765 760);
PAINT MONO (765 760);
FORCEPROP 0 LASTPIN (775 500) $PN A18
J 2
(765 510);
DISPLAY 0.680851 (765 510);
PAINT MONO (765 510);
FORCEPROP 0 LASTPIN (775 450) $PN B18
J 2
(765 460);
DISPLAY 0.680851 (765 460);
PAINT MONO (765 460);
FORCEPROP 0 LASTPIN (775 400) $PN C18
J 2
(765 410);
DISPLAY 0.680851 (765 410);
PAINT MONO (765 410);
FORCEPROP 0 LASTPIN (775 350) $PN A17
J 2
(765 360);
DISPLAY 0.680851 (765 360);
PAINT MONO (765 360);
FORCEPROP 0 LASTPIN (775 300) $PN D18
J 2
(765 310);
DISPLAY 0.680851 (765 310);
PAINT MONO (765 310);
FORCEPROP 0 LASTPIN (775 250) $PN B17
J 2
(765 260);
DISPLAY 0.680851 (765 260);
PAINT MONO (765 260);
FORCEPROP 0 LASTPIN (775 200) $PN C17
J 2
(765 210);
DISPLAY 0.680851 (765 210);
PAINT MONO (765 210);
FORCEPROP 0 LASTPIN (775 150) $PN E18
J 2
(765 160);
DISPLAY 0.680851 (765 160);
PAINT MONO (765 160);
FORCEPROP 0 LASTPIN (2875 1850) $PN B20
J 0
(2885 1860);
DISPLAY 0.680851 (2885 1860);
PAINT MONO (2885 1860);
FORCEPROP 0 LASTPIN (2875 1800) $PN A20
J 0
(2885 1810);
DISPLAY 0.680851 (2885 1810);
PAINT MONO (2885 1810);
FORCEPROP 0 LASTPIN (2875 1750) $PN E19
J 0
(2885 1760);
DISPLAY 0.680851 (2885 1760);
PAINT MONO (2885 1760);
FORCEPROP 0 LASTPIN (2875 1700) $PN D20
J 0
(2885 1710);
DISPLAY 0.680851 (2885 1710);
PAINT MONO (2885 1710);
FORCEPROP 0 LASTPIN (2875 1650) $PN C19
J 0
(2885 1660);
DISPLAY 0.680851 (2885 1660);
PAINT MONO (2885 1660);
FORCEPROP 0 LASTPIN (2875 1600) $PN A19
J 0
(2885 1610);
DISPLAY 0.680851 (2885 1610);
PAINT MONO (2885 1610);
FORCEPROP 0 LASTPIN (2875 1550) $PN C20
J 0
(2885 1560);
DISPLAY 0.680851 (2885 1560);
PAINT MONO (2885 1560);
FORCEPROP 0 LASTPIN (2875 1500) $PN D19
J 0
(2885 1510);
DISPLAY 0.680851 (2885 1510);
PAINT MONO (2885 1510);
FORCEPROP 0 LASTPIN (2875 1350) $PN A11
J 0
(2885 1360);
DISPLAY 0.680851 (2885 1360);
PAINT MONO (2885 1360);
FORCEPROP 0 LASTPIN (2875 1300) $PN C11
J 0
(2885 1310);
DISPLAY 0.680851 (2885 1310);
PAINT MONO (2885 1310);
FORCEPROP 0 LASTPIN (2875 1250) $PN D12
J 0
(2885 1260);
DISPLAY 0.680851 (2885 1260);
PAINT MONO (2885 1260);
FORCEPROP 0 LASTPIN (2875 1200) $PN E13
J 0
(2885 1210);
DISPLAY 0.680851 (2885 1210);
PAINT MONO (2885 1210);
FORCEPROP 0 LASTPIN (2875 1150) $PN D11
J 0
(2885 1160);
DISPLAY 0.680851 (2885 1160);
PAINT MONO (2885 1160);
FORCEPROP 0 LASTPIN (2875 1100) $PN E11
J 0
(2885 1110);
DISPLAY 0.680851 (2885 1110);
PAINT MONO (2885 1110);
FORCEPROP 0 LASTPIN (2875 1050) $PN F13
J 0
(2885 1060);
DISPLAY 0.680851 (2885 1060);
PAINT MONO (2885 1060);
FORCEPROP 0 LASTPIN (2875 1000) $PN E12
J 0
(2885 1010);
DISPLAY 0.680851 (2885 1010);
PAINT MONO (2885 1010);
FORCEPROP 0 LASTPIN (2875 900) $PN D15
J 0
(2885 910);
DISPLAY 0.680851 (2885 910);
PAINT MONO (2885 910);
FORCEPROP 0 LASTPIN (2875 850) $PN A14
J 0
(2885 860);
DISPLAY 0.680851 (2885 860);
PAINT MONO (2885 860);
FORCEPROP 0 LASTPIN (2875 800) $PN E15
J 0
(2885 810);
DISPLAY 0.680851 (2885 810);
PAINT MONO (2885 810);
FORCEPROP 0 LASTPIN (2875 750) $PN A13
J 0
(2885 760);
DISPLAY 0.680851 (2885 760);
PAINT MONO (2885 760);
FORCEPROP 0 LASTPIN (2875 -50) $PN T26
J 0
(2885 -40);
DISPLAY 0.680851 (2885 -40);
PAINT MONO (2885 -40);
FORCEPROP 0 LASTPIN (2875 -100) $PN R24
J 0
(2885 -90);
DISPLAY 0.680851 (2885 -90);
PAINT MONO (2885 -90);
FORCEPROP 0 LASTPIN (2875 2100) $PN AB7
J 0
(2885 2110);
DISPLAY 0.680851 (2885 2110);
PAINT MONO (2885 2110);
FORCEPROP 0 LASTPIN (2875 2050) $PN AB8
J 0
(2885 2060);
DISPLAY 0.680851 (2885 2060);
PAINT MONO (2885 2060);
FORCEPROP 0 LASTPIN (2875 2000) $PN AC8
J 0
(2885 2010);
DISPLAY 0.680851 (2885 2010);
PAINT MONO (2885 2010);
FORCEPROP 0 LASTPIN (2875 1950) $PN AC7
J 0
(2885 1960);
DISPLAY 0.680851 (2885 1960);
PAINT MONO (2885 1960);
FORCEPROP 0 LASTPIN (775 2100) $PN AE7
J 2
(765 2110);
DISPLAY 0.680851 (765 2110);
PAINT MONO (765 2110);
FORCEPROP 0 LASTPIN (775 2050) $PN AF7
J 2
(765 2060);
DISPLAY 0.680851 (765 2060);
PAINT MONO (765 2060);
FORCEPROP 0 LASTPIN (775 2000) $PN AD7
J 2
(765 2010);
DISPLAY 0.680851 (765 2010);
PAINT MONO (765 2010);
FORCEPROP 0 LASTPIN (775 1950) $PN AD8
J 2
(765 1960);
DISPLAY 0.680851 (765 1960);
PAINT MONO (765 1960);
FORCEPROP 0 LASTPIN (2875 3050) $PN F3
J 0
(2885 3060);
DISPLAY 0.680851 (2885 3060);
PAINT MONO (2885 3060);
FORCEPROP 0 LASTPIN (2875 3000) $PN K5
J 0
(2885 3010);
DISPLAY 0.680851 (2885 3010);
PAINT MONO (2885 3010);
FORCEPROP 0 LASTPIN (2875 2950) $PN F1
J 0
(2885 2960);
DISPLAY 0.680851 (2885 2960);
PAINT MONO (2885 2960);
FORCEPROP 0 LASTPIN (2875 2900) $PN H3
J 0
(2885 2910);
DISPLAY 0.680851 (2885 2910);
PAINT MONO (2885 2910);
FORCEPROP 0 LASTPIN (2875 2850) $PN J3
J 0
(2885 2860);
DISPLAY 0.680851 (2885 2860);
PAINT MONO (2885 2860);
FORCEPROP 0 LASTPIN (2875 2800) $PN L1
J 0
(2885 2810);
DISPLAY 0.680851 (2885 2810);
PAINT MONO (2885 2810);
FORCEPROP 0 LASTPIN (2875 2750) $PN M5
J 0
(2885 2760);
DISPLAY 0.680851 (2885 2760);
PAINT MONO (2885 2760);
FORCEPROP 0 LASTPIN (2875 2700) $PN M2
J 0
(2885 2710);
DISPLAY 0.680851 (2885 2710);
PAINT MONO (2885 2710);
FORCEPROP 0 LASTPIN (2875 2650) $PN M1
J 0
(2885 2660);
DISPLAY 0.680851 (2885 2660);
PAINT MONO (2885 2660);
FORCEPROP 0 LASTPIN (2875 2600) $PN N1
J 0
(2885 2610);
DISPLAY 0.680851 (2885 2610);
PAINT MONO (2885 2610);
FORCEPROP 0 LASTPIN (2875 2550) $PN F2
J 0
(2885 2560);
DISPLAY 0.680851 (2885 2560);
PAINT MONO (2885 2560);
FORCEPROP 0 LASTPIN (2875 2500) $PN G1
J 0
(2885 2510);
DISPLAY 0.680851 (2885 2510);
PAINT MONO (2885 2510);
FORCEPROP 0 LASTPIN (2875 2450) $PN L4
J 0
(2885 2460);
DISPLAY 0.680851 (2885 2460);
PAINT MONO (2885 2460);
FORCEPROP 0 LASTPIN (2875 2400) $PN K3
J 0
(2885 2410);
DISPLAY 0.680851 (2885 2410);
PAINT MONO (2885 2410);
FORCEPROP 0 LASTPIN (2875 2350) $PN H1
J 0
(2885 2360);
DISPLAY 0.680851 (2885 2360);
PAINT MONO (2885 2360);
FORCEPROP 0 LASTPIN (2875 2300) $PN M3
J 0
(2885 2310);
DISPLAY 0.680851 (2885 2310);
PAINT MONO (2885 2310);
FORCEPROP 0 LASTPIN (775 2450) $PN N4
J 2
(765 2460);
DISPLAY 0.680851 (765 2460);
PAINT MONO (765 2460);
FORCEPROP 0 LASTPIN (2875 3200) $PN G4
J 0
(2885 3210);
DISPLAY 0.680851 (2885 3210);
PAINT MONO (2885 3210);
FORCEPROP 0 LASTPIN (2875 3150) $PN H5
J 0
(2885 3160);
DISPLAY 0.680851 (2885 3160);
PAINT MONO (2885 3160);
FORCEPROP 0 LASTPIN (2875 3100) $PN G3
J 0
(2885 3110);
DISPLAY 0.680851 (2885 3110);
PAINT MONO (2885 3110);
FORCEPROP 0 LASTPIN (2875 3300) $PN J4
J 0
(2885 3310);
DISPLAY 0.680851 (2885 3310);
PAINT MONO (2885 3310);
FORCEPROP 0 LASTPIN (2875 3600) $PN K2
J 0
(2885 3610);
DISPLAY 0.680851 (2885 3610);
PAINT MONO (2885 3610);
FORCEPROP 0 LASTPIN (2875 3550) $PN K1
J 0
(2885 3560);
DISPLAY 0.680851 (2885 3560);
PAINT MONO (2885 3560);
FORCEPROP 0 LASTPIN (2875 3500) $PN L5
J 0
(2885 3510);
DISPLAY 0.680851 (2885 3510);
PAINT MONO (2885 3510);
FORCEPROP 0 LASTPIN (2875 3400) $PN H2
J 0
(2885 3410);
DISPLAY 0.680851 (2885 3410);
PAINT MONO (2885 3410);
FORCEPROP 0 LASTPIN (2875 2250) $PN N3
J 0
(2885 2260);
DISPLAY 0.680851 (2885 2260);
PAINT MONO (2885 2260);
FORCEPROP 0 LASTPIN (2875 2200) $PN R5
J 0
(2885 2210);
DISPLAY 0.680851 (2885 2210);
PAINT MONO (2885 2210);
FORCEPROP 0 LASTPIN (775 3600) $PN T3
J 2
(765 3610);
DISPLAY 0.680851 (765 3610);
PAINT MONO (765 3610);
FORCEPROP 0 LASTPIN (775 3550) $PN R4
J 2
(765 3560);
DISPLAY 0.680851 (765 3560);
PAINT MONO (765 3560);
FORCEPROP 0 LASTPIN (775 3500) $PN U1
J 2
(765 3510);
DISPLAY 0.680851 (765 3510);
PAINT MONO (765 3510);
FORCEPROP 0 LASTPIN (775 3450) $PN R3
J 2
(765 3460);
DISPLAY 0.680851 (765 3460);
PAINT MONO (765 3460);
FORCEPROP 0 LASTPIN (775 3400) $PN R1
J 2
(765 3410);
DISPLAY 0.680851 (765 3410);
PAINT MONO (765 3410);
FORCEPROP 0 LASTPIN (775 3350) $PN P1
J 2
(765 3360);
DISPLAY 0.680851 (765 3360);
PAINT MONO (765 3360);
FORCEPROP 0 LASTPIN (775 3300) $PN P2
J 2
(765 3310);
DISPLAY 0.680851 (765 3310);
PAINT MONO (765 3310);
FORCEPROP 0 LASTPIN (775 3250) $PN P3
J 2
(765 3260);
DISPLAY 0.680851 (765 3260);
PAINT MONO (765 3260);
FORCEPROP 0 LASTPIN (775 3200) $PN W2
J 2
(765 3210);
DISPLAY 0.680851 (765 3210);
PAINT MONO (765 3210);
FORCEPROP 0 LASTPIN (775 3150) $PN V3
J 2
(765 3160);
DISPLAY 0.680851 (765 3160);
PAINT MONO (765 3160);
FORCEPROP 0 LASTPIN (775 3100) $PN W1
J 2
(765 3110);
DISPLAY 0.680851 (765 3110);
PAINT MONO (765 3110);
FORCEPROP 0 LASTPIN (775 3050) $PN W3
J 2
(765 3060);
DISPLAY 0.680851 (765 3060);
PAINT MONO (765 3060);
FORCEPROP 0 LASTPIN (775 3000) $PN W4
J 2
(765 3010);
DISPLAY 0.680851 (765 3010);
PAINT MONO (765 3010);
FORCEPROP 0 LASTPIN (775 2950) $PN U4
J 2
(765 2960);
DISPLAY 0.680851 (765 2960);
PAINT MONO (765 2960);
FORCEPROP 0 LASTPIN (775 2900) $PN V4
J 2
(765 2910);
DISPLAY 0.680851 (765 2910);
PAINT MONO (765 2910);
FORCEPROP 0 LASTPIN (775 2850) $PN U3
J 2
(765 2860);
DISPLAY 0.680851 (765 2860);
PAINT MONO (765 2860);
FORCEPROP 0 LASTPIN (775 2750) $PN T2
J 2
(765 2760);
DISPLAY 0.680851 (765 2760);
PAINT MONO (765 2760);
FORCEPROP 0 LASTPIN (775 2650) $PN T1
J 2
(765 2660);
DISPLAY 0.680851 (765 2660);
PAINT MONO (765 2660);
FORCEPROP 0 LASTPIN (775 2700) $PN V2
J 2
(765 2710);
DISPLAY 0.680851 (765 2710);
PAINT MONO (765 2710);
FORCEPROP 0 LASTPIN (775 2600) $PN V1
J 2
(765 2610);
DISPLAY 0.680851 (765 2610);
PAINT MONO (765 2610);
FORCEPROP 0 LASTPIN (775 2200) $PN P5
J 2
(765 2210);
DISPLAY 0.680851 (765 2210);
PAINT MONO (765 2210);
FORCEPROP 0 LASTPIN (2875 3450) $PN J1
J 0
(2885 3460);
DISPLAY 0.680851 (2885 3460);
PAINT MONO (2885 3460);
FORCEPROP 0 LASTPIN (2875 3350) $PN J5
J 0
(2885 3360);
DISPLAY 0.680851 (2885 3360);
PAINT MONO (2885 3360);
FORCEPROP 0 LASTPIN (775 2500) $PN L3
J 2
(765 2510);
DISPLAY 0.680851 (765 2510);
PAINT MONO (765 2510);
FORCEPROP 0 LASTPIN (775 2350) $PN T5
J 2
(765 2360);
DISPLAY 0.680851 (765 2360);
PAINT MONO (765 2360);
FORCEPROP 0 LASTPIN (775 2300) $PN U5
J 2
(765 2310);
DISPLAY 0.680851 (765 2310);
PAINT MONO (765 2310);
FORCEPROP 0 LASTPIN (2875 3250) $PN G5
J 0
(2885 3260);
DISPLAY 0.680851 (2885 3260);
PAINT MONO (2885 3260);
FORCEPROP 0 LASTPIN (775 4450) $PN AD6
J 2
(765 4460);
DISPLAY 0.680851 (765 4460);
PAINT MONO (765 4460);
FORCEPROP 0 LASTPIN (775 4500) $PN AD5
J 2
(765 4510);
DISPLAY 0.680851 (765 4510);
PAINT MONO (765 4510);
FORCEPROP 0 LASTPIN (775 4600) $PN A7
J 2
(765 4610);
DISPLAY 0.680851 (765 4610);
PAINT MONO (765 4610);
FORCEPROP 0 LASTPIN (775 4300) $PN AF6
J 2
(765 4310);
DISPLAY 0.680851 (765 4310);
PAINT MONO (765 4310);
FORCEPROP 0 LASTPIN (775 4350) $PN AF5
J 2
(765 4360);
DISPLAY 0.680851 (765 4360);
PAINT MONO (765 4360);
FORCEPROP 0 LASTPIN (2875 4550) $PN AE5
J 0
(2885 4560);
DISPLAY 0.680851 (2885 4560);
PAINT MONO (2885 4560);
FORCEPROP 0 LASTPIN (2875 4600) $PN AE4
J 0
(2885 4610);
DISPLAY 0.680851 (2885 4610);
PAINT MONO (2885 4610);
FORCEPROP 0 LASTPIN (775 4150) $PN AE2
J 2
(765 4160);
DISPLAY 0.680851 (765 4160);
PAINT MONO (765 4160);
FORCEPROP 0 LASTPIN (775 4200) $PN AE1
J 2
(765 4210);
DISPLAY 0.680851 (765 4210);
PAINT MONO (765 4210);
FORCEPROP 0 LASTPIN (775 4000) $PN AD3
J 2
(765 4010);
DISPLAY 0.680851 (765 4010);
PAINT MONO (765 4010);
FORCEPROP 0 LASTPIN (775 4050) $PN AD2
J 2
(765 4060);
DISPLAY 0.680851 (765 4060);
PAINT MONO (765 4060);
FORCEPROP 0 LASTPIN (2875 4150) $PN AF3
J 0
(2885 4160);
DISPLAY 0.680851 (2885 4160);
PAINT MONO (2885 4160);
FORCEPROP 0 LASTPIN (2875 4200) $PN AF2
J 0
(2885 4210);
DISPLAY 0.680851 (2885 4210);
PAINT MONO (2885 4210);
FORCEPROP 0 LAST $SEC 1
J 0
(950 5075);
DISPLAY 0.680851 (950 5075);
PAINT MONO (950 5075);
DISPLAY INVISIBLE (950 5075);
FORCEPROP 0 LAST CDS_SEC 1
J 0
(950 5075);
DISPLAY 0.680851 (950 5075);
DISPLAY INVISIBLE (950 5075);
FORCEADD OFFPAGE..1
(-2325 1950);
FORCEPROP 2 LAST $XR0 10 
J 0
(-2606 1950);
DISPLAY 0.638298 (-2606 1950);
PAINT MONO (-2606 1950);
FORCEPROP 2 LAST $XR1 12 
J 0
(-2696 1950);
DISPLAY 0.638298 (-2696 1950);
PAINT MONO (-2696 1950);
FORCEPROP 2 LAST CDS_LIB standard
J 0
(-2325 1950);
DISPLAY INVISIBLE (-2325 1950);
FORCEPROP 2 LAST PATH I439
J 0
(-2275 2025);
DISPLAY 0.680851 (-2275 2025);
DISPLAY INVISIBLE (-2275 2025);
FORCEPROP 1 LAST COMMENT_BODY TRUE
J 0
(-2200 1850);
DISPLAY 0.872340 (-2200 1850);
PAINT PEACH (-2200 1850);
DISPLAY INVISIBLE (-2200 1850);
FORCEPROP 1 LAST OFFPAGE TRUE
J 0
(-2000 1825);
DISPLAY 0.872340 (-2000 1825);
PAINT GREEN (-2000 1825);
DISPLAY INVISIBLE (-2000 1825);
FORCEADD OFFPAGE..2
(-200 -325);
FORCEPROP 2 LAST $XR1 12 
J 0
(79 -325);
DISPLAY 0.638298 (79 -325);
PAINT MONO (79 -325);
FORCEPROP 2 LAST $XR0 10 
J 0
(-11 -325);
DISPLAY 0.638298 (-11 -325);
PAINT MONO (-11 -325);
FORCEPROP 2 LAST PATH I44
J 0
(50 -275);
DISPLAY 1.021277 (50 -275);
DISPLAY INVISIBLE (50 -275);
FORCEPROP 1 LAST COMMENT_BODY TRUE
J 0
(-245 -420);
DISPLAY 0.872340 (-245 -420);
PAINT PEACH (-245 -420);
DISPLAY INVISIBLE (-245 -420);
FORCEPROP 1 LAST OFFPAGE TRUE
J 0
(125 -450);
DISPLAY 0.872340 (125 -450);
PAINT GREEN (125 -450);
DISPLAY INVISIBLE (125 -450);
FORCEPROP 2 LAST CDS_LIB standard
J 0
(-200 -325);
DISPLAY INVISIBLE (-200 -325);
FORCEADD OFFPAGE..1
(-2325 2100);
FORCEPROP 2 LAST $XR0 10 
J 0
(-2576 2100);
DISPLAY 0.638298 (-2576 2100);
PAINT MONO (-2576 2100);
FORCEPROP 1 LAST OFFPAGE TRUE
J 0
(-2000 1975);
DISPLAY 0.872340 (-2000 1975);
PAINT GREEN (-2000 1975);
DISPLAY INVISIBLE (-2000 1975);
FORCEPROP 1 LAST COMMENT_BODY TRUE
J 0
(-2200 2000);
DISPLAY 0.872340 (-2200 2000);
PAINT PEACH (-2200 2000);
DISPLAY INVISIBLE (-2200 2000);
FORCEPROP 2 LAST CDS_LIB standard
J 0
(-2325 2100);
DISPLAY INVISIBLE (-2325 2100);
FORCEPROP 2 LAST PATH I440
J 0
(-2575 2150);
DISPLAY 0.680851 (-2575 2150);
DISPLAY INVISIBLE (-2575 2150);
FORCEADD Q_RES..1
(-850 2100);
FORCEPROP 1 LAST MATERIAL CHIP
J 0
(-1150 2100);
DISPLAY 0.510638 (-1150 2100);
PAINT SKYBLUE (-1150 2100);
FORCEPROP 1 LAST VALUE 33.2
J 0
(-750 2100);
DISPLAY 0.510638 (-750 2100);
PAINT SKYBLUE (-750 2100);
FORCEPROP 2 LAST CDS_LIB pure_quanta
J 0
(-850 2100);
DISPLAY INVISIBLE (-850 2100);
FORCEPROP 1 LAST PATH I441
J 0
(-900 2250);
DISPLAY 0.978723 (-900 2250);
PAINT WHITE (-900 2250);
DISPLAY INVISIBLE (-900 2250);
FORCEPROP 1 LAST TOLERANCE 1%
J 0
(-725 2100);
DISPLAY 0.510638 (-725 2100);
PAINT SKYBLUE (-725 2100);
DISPLAY INVISIBLE (-725 2100);
FORCEPROP 1 LAST PART_NUMBER CS03322FB03
J 0
(-900 2200);
DISPLAY 0.510638 (-900 2200);
PAINT WHITE (-900 2200);
DISPLAY INVISIBLE (-900 2200);
FORCEPROP 1 LAST WATTAGE 1/16W
J 2
(-875 1950);
DISPLAY 0.510638 (-875 1950);
PAINT SKYBLUE (-875 1950);
DISPLAY INVISIBLE (-875 1950);
FORCEPROP 1 LAST PACK_TYPE 0402LF
J 0
(-600 1950);
DISPLAY 0.510638 (-600 1950);
PAINT SKYBLUE (-600 1950);
DISPLAY INVISIBLE (-600 1950);
FORCEPROP 1 LAST $LOCATION R310
J 0
(-1050 2100);
DISPLAY 0.702128 (-1050 2100);
PAINT YELLOW (-1050 2100);
FORCEPROP 1 LASTPIN (-950 2100) $PN 1
J 0
(-938 2112);
DISPLAY 0.787234 (-938 2112);
PAINT MONO (-938 2112);
FORCEPROP 1 LASTPIN (-750 2100) $PN 2
J 0
(-788 2112);
DISPLAY 0.787234 (-788 2112);
PAINT MONO (-788 2112);
FORCEPROP 0 LAST CDS_LOCATION R310
J 0
(-1025 2150);
DISPLAY 0.680851 (-1025 2150);
DISPLAY INVISIBLE (-1025 2150);
FORCEPROP 0 LAST $SEC 1
J 0
(-1025 2150);
DISPLAY 0.680851 (-1025 2150);
PAINT MONO (-1025 2150);
DISPLAY INVISIBLE (-1025 2150);
FORCEPROP 0 LAST CDS_SEC 1
J 0
(-1025 2150);
DISPLAY 0.680851 (-1025 2150);
DISPLAY INVISIBLE (-1025 2150);
FORCEADD Q_RES..1
(3825 2100);
FORCEPROP 1 LAST VALUE 22
J 2
(3975 2100);
DISPLAY 0.510638 (3975 2100);
FORCEPROP 1 LAST PART_NUMBER CS02202FB02
J 0
(3750 2150);
DISPLAY 0.510638 (3750 2150);
FORCEPROP 1 LAST MATERIAL CHIP
J 0
(4000 2100);
DISPLAY 0.510638 (4000 2100);
PAINT SKYBLUE (4000 2100);
FORCEPROP 1 LAST PACK_TYPE 0402LF
J 0
(4075 1950);
DISPLAY 0.510638 (4075 1950);
DISPLAY INVISIBLE (4075 1950);
FORCEPROP 1 LAST WATTAGE 1/16W
J 2
(3800 1950);
DISPLAY 0.510638 (3800 1950);
DISPLAY INVISIBLE (3800 1950);
FORCEPROP 1 LAST TOLERANCE 1%
J 0
(3825 2000);
DISPLAY 0.510638 (3825 2000);
DISPLAY INVISIBLE (3825 2000);
FORCEPROP 1 LAST PATH I442
J 0
(3775 2250);
DISPLAY 0.978723 (3775 2250);
PAINT WHITE (3775 2250);
DISPLAY INVISIBLE (3775 2250);
FORCEPROP 2 LAST CDS_LIB pure_quanta
J 0
(3825 2100);
DISPLAY INVISIBLE (3825 2100);
FORCEPROP 1 LAST LOCATION R128
J 0
(3650 2100);
DISPLAY 0.638298 (3650 2100);
FORCEPROP 1 LASTPIN (3725 2100) $PN 1
J 0
(3737 2112);
DISPLAY 0.787234 (3737 2112);
PAINT MONO (3737 2112);
FORCEPROP 1 LASTPIN (3925 2100) $PN 2
J 0
(3887 2112);
DISPLAY 0.787234 (3887 2112);
PAINT MONO (3887 2112);
FORCEPROP 0 LAST $SEC 1
J 0
(3775 2150);
DISPLAY 0.680851 (3775 2150);
PAINT MONO (3775 2150);
DISPLAY INVISIBLE (3775 2150);
FORCEPROP 0 LAST CDS_SEC 1
J 0
(3775 2150);
DISPLAY 0.680851 (3775 2150);
DISPLAY INVISIBLE (3775 2150);
FORCEADD Q_RES..1
(3825 1950);
FORCEPROP 1 LAST MATERIAL CHIP
J 0
(4000 1950);
DISPLAY 0.510638 (4000 1950);
PAINT SKYBLUE (4000 1950);
FORCEPROP 1 LAST VALUE 22
J 2
(3975 1950);
DISPLAY 0.510638 (3975 1950);
FORCEPROP 2 LAST CDS_LIB pure_quanta
J 0
(3825 1950);
DISPLAY INVISIBLE (3825 1950);
FORCEPROP 1 LAST PATH I443
J 0
(3775 2100);
DISPLAY 0.978723 (3775 2100);
PAINT WHITE (3775 2100);
DISPLAY INVISIBLE (3775 2100);
FORCEPROP 1 LAST PART_NUMBER CS02202FB02
J 0
(3825 2000);
DISPLAY 0.510638 (3825 2000);
DISPLAY INVISIBLE (3825 2000);
FORCEPROP 1 LAST TOLERANCE 1%
J 0
(3825 1850);
DISPLAY 0.510638 (3825 1850);
DISPLAY INVISIBLE (3825 1850);
FORCEPROP 1 LAST WATTAGE 1/16W
J 2
(3800 1800);
DISPLAY 0.510638 (3800 1800);
DISPLAY INVISIBLE (3800 1800);
FORCEPROP 1 LAST PACK_TYPE 0402LF
J 0
(4075 1800);
DISPLAY 0.510638 (4075 1800);
DISPLAY INVISIBLE (4075 1800);
FORCEPROP 1 LAST LOCATION R131
J 0
(3650 1950);
DISPLAY 0.638298 (3650 1950);
FORCEPROP 1 LASTPIN (3725 1950) $PN 1
J 0
(3737 1962);
DISPLAY 0.787234 (3737 1962);
PAINT MONO (3737 1962);
FORCEPROP 1 LASTPIN (3925 1950) $PN 2
J 0
(3887 1962);
DISPLAY 0.787234 (3887 1962);
PAINT MONO (3887 1962);
FORCEPROP 0 LAST $SEC 1
J 0
(3650 2000);
DISPLAY 0.680851 (3650 2000);
PAINT MONO (3650 2000);
DISPLAY INVISIBLE (3650 2000);
FORCEPROP 0 LAST CDS_SEC 1
J 0
(3650 2000);
DISPLAY 0.680851 (3650 2000);
DISPLAY INVISIBLE (3650 2000);
FORCEADD Q_RES..1
(3825 2000);
FORCEPROP 1 LAST VALUE 22
J 2
(3975 2000);
DISPLAY 0.510638 (3975 2000);
FORCEPROP 1 LAST MATERIAL CHIP
J 0
(4000 2000);
DISPLAY 0.510638 (4000 2000);
PAINT SKYBLUE (4000 2000);
FORCEPROP 2 LAST CDS_LIB pure_quanta
J 0
(3825 2000);
DISPLAY INVISIBLE (3825 2000);
FORCEPROP 1 LAST PATH I444
J 0
(3775 2150);
DISPLAY 0.978723 (3775 2150);
PAINT WHITE (3775 2150);
DISPLAY INVISIBLE (3775 2150);
FORCEPROP 1 LAST PACK_TYPE 0402LF
J 0
(4075 1850);
DISPLAY 0.510638 (4075 1850);
DISPLAY INVISIBLE (4075 1850);
FORCEPROP 1 LAST WATTAGE 1/16W
J 2
(3800 1850);
DISPLAY 0.510638 (3800 1850);
DISPLAY INVISIBLE (3800 1850);
FORCEPROP 1 LAST TOLERANCE 1%
J 0
(3825 1900);
DISPLAY 0.510638 (3825 1900);
DISPLAY INVISIBLE (3825 1900);
FORCEPROP 1 LAST PART_NUMBER CS02202FB02
J 0
(3825 2050);
DISPLAY 0.510638 (3825 2050);
DISPLAY INVISIBLE (3825 2050);
FORCEPROP 1 LAST LOCATION R130
J 0
(3650 2000);
DISPLAY 0.638298 (3650 2000);
FORCEPROP 1 LASTPIN (3725 2000) $PN 1
J 0
(3737 2012);
DISPLAY 0.787234 (3737 2012);
PAINT MONO (3737 2012);
FORCEPROP 1 LASTPIN (3925 2000) $PN 2
J 0
(3887 2012);
DISPLAY 0.787234 (3887 2012);
PAINT MONO (3887 2012);
FORCEPROP 0 LAST $SEC 1
J 0
(3650 2050);
DISPLAY 0.680851 (3650 2050);
PAINT MONO (3650 2050);
DISPLAY INVISIBLE (3650 2050);
FORCEPROP 0 LAST CDS_SEC 1
J 0
(3650 2050);
DISPLAY 0.680851 (3650 2050);
DISPLAY INVISIBLE (3650 2050);
FORCEADD Q_RES..1
(3825 2050);
FORCEPROP 1 LAST VALUE 22
J 2
(3975 2050);
DISPLAY 0.510638 (3975 2050);
FORCEPROP 1 LAST MATERIAL CHIP
J 0
(4000 2050);
DISPLAY 0.510638 (4000 2050);
PAINT SKYBLUE (4000 2050);
FORCEPROP 1 LAST PART_NUMBER CS02202FB02
J 0
(3825 2100);
DISPLAY 0.510638 (3825 2100);
DISPLAY INVISIBLE (3825 2100);
FORCEPROP 1 LAST TOLERANCE 1%
J 0
(3825 1950);
DISPLAY 0.510638 (3825 1950);
DISPLAY INVISIBLE (3825 1950);
FORCEPROP 1 LAST WATTAGE 1/16W
J 2
(3800 1900);
DISPLAY 0.510638 (3800 1900);
DISPLAY INVISIBLE (3800 1900);
FORCEPROP 1 LAST PACK_TYPE 0402LF
J 0
(4075 1900);
DISPLAY 0.510638 (4075 1900);
DISPLAY INVISIBLE (4075 1900);
FORCEPROP 1 LAST PATH I445
J 0
(3775 2200);
DISPLAY 0.978723 (3775 2200);
PAINT WHITE (3775 2200);
DISPLAY INVISIBLE (3775 2200);
FORCEPROP 2 LAST CDS_LIB pure_quanta
J 0
(3825 2050);
DISPLAY INVISIBLE (3825 2050);
FORCEPROP 1 LAST LOCATION R129
J 0
(3650 2050);
DISPLAY 0.638298 (3650 2050);
FORCEPROP 1 LASTPIN (3725 2050) $PN 1
J 0
(3737 2062);
DISPLAY 0.787234 (3737 2062);
PAINT MONO (3737 2062);
FORCEPROP 1 LASTPIN (3925 2050) $PN 2
J 0
(3887 2062);
DISPLAY 0.787234 (3887 2062);
PAINT MONO (3887 2062);
FORCEPROP 0 LAST $SEC 1
J 0
(3650 2100);
DISPLAY 0.680851 (3650 2100);
PAINT MONO (3650 2100);
DISPLAY INVISIBLE (3650 2100);
FORCEPROP 0 LAST CDS_SEC 1
J 0
(3650 2100);
DISPLAY 0.680851 (3650 2100);
DISPLAY INVISIBLE (3650 2100);
FORCEADD OFFPAGE..1
(-2325 2050);
FORCEPROP 2 LAST $XR1 12 
J 0
(-2666 2050);
DISPLAY 0.638298 (-2666 2050);
PAINT MONO (-2666 2050);
FORCEPROP 2 LAST $XR0 10 
J 0
(-2576 2050);
DISPLAY 0.638298 (-2576 2050);
PAINT MONO (-2576 2050);
FORCEPROP 2 LAST PATH I446
J 0
(-2575 2100);
DISPLAY 0.680851 (-2575 2100);
DISPLAY INVISIBLE (-2575 2100);
FORCEPROP 1 LAST COMMENT_BODY TRUE
J 0
(-2200 1950);
DISPLAY 0.872340 (-2200 1950);
PAINT PEACH (-2200 1950);
DISPLAY INVISIBLE (-2200 1950);
FORCEPROP 1 LAST OFFPAGE TRUE
J 0
(-2000 1925);
DISPLAY 0.872340 (-2000 1925);
PAINT GREEN (-2000 1925);
DISPLAY INVISIBLE (-2000 1925);
FORCEPROP 2 LAST CDS_LIB standard
J 0
(-2325 2050);
DISPLAY INVISIBLE (-2325 2050);
FORCEADD Q_RES..1
(-850 2050);
FORCEPROP 1 LAST MATERIAL CHIP
J 0
(-1150 2050);
DISPLAY 0.510638 (-1150 2050);
PAINT SKYBLUE (-1150 2050);
FORCEPROP 1 LAST VALUE 33.2
J 0
(-750 2050);
DISPLAY 0.510638 (-750 2050);
PAINT SKYBLUE (-750 2050);
FORCEPROP 1 LAST PACK_TYPE 0402LF
J 0
(-600 1900);
DISPLAY 0.510638 (-600 1900);
PAINT SKYBLUE (-600 1900);
DISPLAY INVISIBLE (-600 1900);
FORCEPROP 1 LAST WATTAGE 1/16W
J 2
(-875 1900);
DISPLAY 0.510638 (-875 1900);
PAINT SKYBLUE (-875 1900);
DISPLAY INVISIBLE (-875 1900);
FORCEPROP 1 LAST PART_NUMBER CS03322FB03
J 0
(-900 2150);
DISPLAY 0.510638 (-900 2150);
PAINT WHITE (-900 2150);
DISPLAY INVISIBLE (-900 2150);
FORCEPROP 1 LAST TOLERANCE 1%
J 0
(-725 2050);
DISPLAY 0.510638 (-725 2050);
PAINT SKYBLUE (-725 2050);
DISPLAY INVISIBLE (-725 2050);
FORCEPROP 1 LAST PATH I447
J 0
(-900 2200);
DISPLAY 0.978723 (-900 2200);
PAINT WHITE (-900 2200);
DISPLAY INVISIBLE (-900 2200);
FORCEPROP 2 LAST CDS_LIB pure_quanta
J 0
(-850 2050);
DISPLAY INVISIBLE (-850 2050);
FORCEPROP 1 LAST $LOCATION R311
J 0
(-1050 2050);
DISPLAY 0.787234 (-1050 2050);
PAINT YELLOW (-1050 2050);
FORCEPROP 1 LASTPIN (-950 2050) $PN 1
J 0
(-938 2062);
DISPLAY 0.787234 (-938 2062);
PAINT MONO (-938 2062);
FORCEPROP 1 LASTPIN (-750 2050) $PN 2
J 0
(-788 2062);
DISPLAY 0.787234 (-788 2062);
PAINT MONO (-788 2062);
FORCEPROP 0 LAST CDS_LOCATION R311
J 0
(-1000 2100);
DISPLAY 0.680851 (-1000 2100);
DISPLAY INVISIBLE (-1000 2100);
FORCEPROP 0 LAST $SEC 1
J 0
(-1000 2100);
DISPLAY 0.680851 (-1000 2100);
PAINT MONO (-1000 2100);
DISPLAY INVISIBLE (-1000 2100);
FORCEPROP 0 LAST CDS_SEC 1
J 0
(-1000 2100);
DISPLAY 0.680851 (-1000 2100);
DISPLAY INVISIBLE (-1000 2100);
FORCEADD Q_CAP..1
(-1875 2625);
FORCEPROP 1 LAST PACK_TYPE 0402
J 0
(-1825 2475);
DISPLAY 0.510638 (-1825 2475);
PAINT SKYBLUE (-1825 2475);
FORCEPROP 1 LAST VALUE 0.1UF
J 0
(-1825 2675);
DISPLAY 0.510638 (-1825 2675);
PAINT SKYBLUE (-1825 2675);
FORCEPROP 1 LAST VOLTAGE 25V
J 0
(-1825 2625);
DISPLAY 0.510638 (-1825 2625);
PAINT SKYBLUE (-1825 2625);
FORCEPROP 1 LAST MATERIAL X7R
J 0
(-1825 2525);
DISPLAY 0.510638 (-1825 2525);
PAINT SKYBLUE (-1825 2525);
FORCEPROP 1 LAST PART_NUMBER CH4104K1B00
J 0
(-1825 2425);
DISPLAY 0.510638 (-1825 2425);
PAINT WHITE (-1825 2425);
FORCEPROP 1 LAST TOLERANCE 10%
J 0
(-1825 2575);
DISPLAY 0.510638 (-1825 2575);
PAINT SKYBLUE (-1825 2575);
FORCEPROP 2 LAST CDS_LIB pure_quanta
J 0
(-1875 2625);
DISPLAY INVISIBLE (-1875 2625);
FORCEPROP 1 LAST PATH I448
J 0
(-1825 2775);
DISPLAY 0.978723 (-1825 2775);
PAINT WHITE (-1825 2775);
DISPLAY INVISIBLE (-1825 2775);
FORCEPROP 1 LAST LOCATION C22
J 0
(-1825 2725);
DISPLAY 0.702128 (-1825 2725);
PAINT YELLOW (-1825 2725);
FORCEPROP 1 LASTPIN (-1875 2725) $PN 1
J 0
(-1865 2705);
DISPLAY 0.787234 (-1865 2705);
PAINT MONO (-1865 2705);
FORCEPROP 1 LASTPIN (-1875 2525) $PN 2
J 0
(-1865 2505);
DISPLAY 0.787234 (-1865 2505);
PAINT MONO (-1865 2505);
FORCEPROP 0 LAST $SEC 1
J 0
(-1825 2775);
DISPLAY 0.680851 (-1825 2775);
PAINT MONO (-1825 2775);
DISPLAY INVISIBLE (-1825 2775);
FORCEPROP 0 LAST CDS_SEC 1
J 0
(-1825 2775);
DISPLAY 0.680851 (-1825 2775);
DISPLAY INVISIBLE (-1825 2775);
FORCEADD OFFPAGE..2
(5925 -950);
FORCEPROP 2 LAST $XR1 12 
J 0
(6204 -950);
DISPLAY 0.638298 (6204 -950);
PAINT MONO (6204 -950);
FORCEPROP 2 LAST $XR0 34 
J 0
(6114 -950);
DISPLAY 0.638298 (6114 -950);
PAINT MONO (6114 -950);
FORCEPROP 2 LAST CDS_LIB standard
J 0
(5925 -950);
DISPLAY INVISIBLE (5925 -950);
FORCEPROP 2 LAST PATH I449
J 0
(6100 -875);
DISPLAY 0.680851 (6100 -875);
DISPLAY INVISIBLE (6100 -875);
FORCEPROP 1 LAST OFFPAGE TRUE
J 0
(6250 -1075);
DISPLAY 0.872340 (6250 -1075);
PAINT GREEN (6250 -1075);
DISPLAY INVISIBLE (6250 -1075);
FORCEPROP 1 LAST COMMENT_BODY TRUE
J 0
(5880 -1045);
DISPLAY 0.872340 (5880 -1045);
PAINT PEACH (5880 -1045);
DISPLAY INVISIBLE (5880 -1045);
FORCEADD Q_RES..1
(4600 -950);
FORCEPROP 1 LAST VALUE 4.7K
J 2
(4475 -950);
DISPLAY 0.510638 (4475 -950);
PAINT SKYBLUE (4475 -950);
FORCEPROP 1 LAST MATERIAL EMPTY
J 0
(4725 -950);
DISPLAY 0.510638 (4725 -950);
PAINT RED (4725 -950);
FORCEPROP 1 LAST PART_NUMBER CS24702FB06
J 0
(4550 -850);
DISPLAY 0.510638 (4550 -850);
PAINT WHITE (4550 -850);
DISPLAY INVISIBLE (4550 -850);
FORCEPROP 1 LAST TOLERANCE 1%
J 0
(4600 -1050);
DISPLAY 0.510638 (4600 -1050);
PAINT SKYBLUE (4600 -1050);
DISPLAY INVISIBLE (4600 -1050);
FORCEPROP 1 LAST WATTAGE 1/16W
J 2
(4575 -1100);
DISPLAY 0.510638 (4575 -1100);
PAINT SKYBLUE (4575 -1100);
DISPLAY INVISIBLE (4575 -1100);
FORCEPROP 1 LAST PACK_TYPE 0402LF
J 0
(4850 -1100);
DISPLAY 0.510638 (4850 -1100);
PAINT SKYBLUE (4850 -1100);
DISPLAY INVISIBLE (4850 -1100);
FORCEPROP 1 LAST PATH I454
J 0
(4550 -800);
DISPLAY 0.978723 (4550 -800);
PAINT WHITE (4550 -800);
DISPLAY INVISIBLE (4550 -800);
FORCEPROP 2 LAST CDS_LIB pure_quanta
J 0
(4600 -950);
DISPLAY INVISIBLE (4600 -950);
FORCEPROP 1 LAST $LOCATION R400
J 0
(4250 -950);
DISPLAY 0.702128 (4250 -950);
PAINT YELLOW (4250 -950);
FORCEPROP 1 LASTPIN (4500 -950) $PN 1
J 0
(4512 -938);
DISPLAY 0.787234 (4512 -938);
PAINT MONO (4512 -938);
FORCEPROP 1 LASTPIN (4700 -950) $PN 2
J 0
(4662 -938);
DISPLAY 0.787234 (4662 -938);
PAINT MONO (4662 -938);
FORCEPROP 0 LAST CDS_LOCATION R400
J 0
(4250 -900);
DISPLAY 0.680851 (4250 -900);
DISPLAY INVISIBLE (4250 -900);
FORCEPROP 0 LAST $SEC 1
J 0
(4250 -900);
DISPLAY 0.680851 (4250 -900);
PAINT MONO (4250 -900);
DISPLAY INVISIBLE (4250 -900);
FORCEPROP 0 LAST CDS_SEC 1
J 0
(4250 -900);
DISPLAY 0.680851 (4250 -900);
DISPLAY INVISIBLE (4250 -900);
FORCEADD VCCAUX15..1
(4200 -800);
FORCEPROP 3 LASTPIN (4200 -850) SIG_NAME P3V3_AUX\g
J 0
(4210 -840);
DISPLAY 0.659574 (4210 -840);
PAINT MONO (4210 -840);
DISPLAY INVISIBLE (4210 -840);
FORCEPROP 1 LAST HDL_POWER P3V3_AUX
J 1
(4200 -750);
DISPLAY 0.702128 (4200 -750);
PAINT GREEN (4200 -750);
FORCEPROP 2 LAST CDS_LIB logical_power
J 0
(4200 -800);
DISPLAY INVISIBLE (4200 -800);
FORCEPROP 1 LAST PATH I455
J 0
(4250 -775);
DISPLAY 0.872340 (4250 -775);
PAINT AQUA (4250 -775);
DISPLAY INVISIBLE (4250 -775);
FORCEADD Q_RES..2
(-1275 -625);
FORCEPROP 1 LAST PART_NUMBER CS34702FB01
J 0
(-1235 -750);
DISPLAY 0.510638 (-1235 -750);
PAINT WHITE (-1235 -750);
FORCEPROP 1 LAST PACK_TYPE 0402LF
J 0
(-1235 -800);
DISPLAY 0.510638 (-1235 -800);
PAINT SKYBLUE (-1235 -800);
FORCEPROP 1 LAST VALUE 47K
J 0
(-1230 -550);
DISPLAY 0.510638 (-1230 -550);
PAINT SKYBLUE (-1230 -550);
FORCEPROP 1 LAST TOLERANCE 1%
J 0
(-1230 -600);
DISPLAY 0.510638 (-1230 -600);
PAINT SKYBLUE (-1230 -600);
FORCEPROP 1 LAST WATTAGE 1/16W
J 0
(-1235 -650);
DISPLAY 0.510638 (-1235 -650);
PAINT SKYBLUE (-1235 -650);
FORCEPROP 1 LAST MATERIAL CHIP
J 0
(-1235 -700);
DISPLAY 0.510638 (-1235 -700);
PAINT SKYBLUE (-1235 -700);
FORCEPROP 1 LAST PATH I456
J 0
(-1225 -450);
DISPLAY 0.978723 (-1225 -450);
PAINT WHITE (-1225 -450);
DISPLAY INVISIBLE (-1225 -450);
FORCEPROP 2 LAST CDS_LIB pure_quanta
J 0
(-1275 -625);
DISPLAY INVISIBLE (-1275 -625);
FORCEPROP 1 LAST $LOCATION R312
J 0
(-1230 -500);
DISPLAY 0.702128 (-1230 -500);
PAINT YELLOW (-1230 -500);
FORCEPROP 1 LASTPIN (-1275 -525) $PN 1
J 0
(-1270 -563);
DISPLAY 0.787234 (-1270 -563);
PAINT MONO (-1270 -563);
FORCEPROP 1 LASTPIN (-1275 -725) $PN 2
J 0
(-1270 -715);
DISPLAY 0.787234 (-1270 -715);
PAINT MONO (-1270 -715);
FORCEPROP 0 LAST CDS_LOCATION R312
J 0
(-1225 -450);
DISPLAY 0.680851 (-1225 -450);
DISPLAY INVISIBLE (-1225 -450);
FORCEPROP 0 LAST $SEC 1
J 0
(-1225 -450);
DISPLAY 0.680851 (-1225 -450);
PAINT MONO (-1225 -450);
DISPLAY INVISIBLE (-1225 -450);
FORCEPROP 0 LAST CDS_SEC 1
J 0
(-1225 -450);
DISPLAY 0.680851 (-1225 -450);
DISPLAY INVISIBLE (-1225 -450);
FORCEADD UNIVERSAL_GND..1
(-1275 -825);
FORCEPROP 3 LASTPIN (-1275 -775) SIG_NAME GND\g
J 0
(-1265 -765);
DISPLAY 0.659574 (-1265 -765);
PAINT MONO (-1265 -765);
DISPLAY INVISIBLE (-1265 -765);
FORCEPROP 1 LAST HDL_POWER GND
J 1
(-1250 -900);
DISPLAY 0.702128 (-1250 -900);
PAINT GREEN (-1250 -900);
DISPLAY INVISIBLE (-1250 -900);
FORCEPROP 1 LAST PATH I457
J 0
(-1200 -825);
DISPLAY 0.872340 (-1200 -825);
PAINT AQUA (-1200 -825);
DISPLAY INVISIBLE (-1200 -825);
FORCEPROP 2 LAST CDS_LIB logical_power
J 0
(-1275 -825);
DISPLAY INVISIBLE (-1275 -825);
FORCEADD Q_RES..1
(-1400 25);
FORCEPROP 1 LAST MATERIAL CHIP
J 2
(-1025 25);
DISPLAY 0.510638 (-1025 25);
PAINT SKYBLUE (-1025 25);
FORCEPROP 1 LAST VALUE 33.2
J 0
(-1275 25);
DISPLAY 0.510638 (-1275 25);
PAINT SKYBLUE (-1275 25);
FORCEPROP 2 LAST CDS_LIB pure_quanta
J 0
(-1400 25);
DISPLAY INVISIBLE (-1400 25);
FORCEPROP 1 LAST PATH I458
J 0
(-1450 175);
DISPLAY 0.978723 (-1450 175);
PAINT WHITE (-1450 175);
DISPLAY INVISIBLE (-1450 175);
FORCEPROP 1 LAST PACK_TYPE 0402LF
J 0
(-1150 -125);
DISPLAY 0.510638 (-1150 -125);
PAINT SKYBLUE (-1150 -125);
DISPLAY INVISIBLE (-1150 -125);
FORCEPROP 1 LAST WATTAGE 1/16W
J 2
(-1425 -125);
DISPLAY 0.510638 (-1425 -125);
PAINT SKYBLUE (-1425 -125);
DISPLAY INVISIBLE (-1425 -125);
FORCEPROP 1 LAST PART_NUMBER CS03322FB03
J 0
(-1450 125);
DISPLAY 0.510638 (-1450 125);
PAINT WHITE (-1450 125);
DISPLAY INVISIBLE (-1450 125);
FORCEPROP 1 LAST TOLERANCE 1%
J 0
(-1275 25);
DISPLAY 0.510638 (-1275 25);
PAINT SKYBLUE (-1275 25);
DISPLAY INVISIBLE (-1275 25);
FORCEPROP 1 LAST $LOCATION R880
J 2
(-1550 25);
DISPLAY 0.702128 (-1550 25);
PAINT YELLOW (-1550 25);
FORCEPROP 1 LASTPIN (-1500 25) $PN 1
J 0
(-1488 37);
DISPLAY 0.787234 (-1488 37);
PAINT MONO (-1488 37);
FORCEPROP 1 LASTPIN (-1300 25) $PN 2
J 0
(-1338 37);
DISPLAY 0.787234 (-1338 37);
PAINT MONO (-1338 37);
FORCEPROP 0 LAST CDS_LOCATION R880
J 0
(-1575 75);
DISPLAY 0.680851 (-1575 75);
DISPLAY INVISIBLE (-1575 75);
FORCEPROP 0 LAST $SEC 1
J 0
(-1575 75);
DISPLAY 0.680851 (-1575 75);
PAINT MONO (-1575 75);
DISPLAY INVISIBLE (-1575 75);
FORCEPROP 0 LAST CDS_SEC 1
J 0
(-1575 75);
DISPLAY 0.680851 (-1575 75);
DISPLAY INVISIBLE (-1575 75);
FORCEADD Q_RES..1
(-200 2200);
FORCEPROP 1 LAST PART_NUMBER CS12402FB01
J 0
(-400 2275);
DISPLAY 0.510638 (-400 2275);
PAINT WHITE (-400 2275);
FORCEPROP 1 LAST VALUE 240
J 2
(25 2200);
DISPLAY 0.510638 (25 2200);
PAINT SKYBLUE (25 2200);
FORCEPROP 1 LAST TOLERANCE 1%
J 0
(25 2250);
DISPLAY 0.510638 (25 2250);
PAINT SKYBLUE (25 2250);
FORCEPROP 1 LAST MATERIAL CHIP
J 0
(-400 2250);
DISPLAY 0.510638 (-400 2250);
PAINT SKYBLUE (-400 2250);
FORCEPROP 1 LAST WATTAGE 1/16W
J 2
(0 2250);
DISPLAY 0.510638 (0 2250);
PAINT SKYBLUE (0 2250);
DISPLAY INVISIBLE (0 2250);
FORCEPROP 1 LAST PACK_TYPE 0402LF
J 0
(75 2200);
DISPLAY 0.510638 (75 2200);
PAINT SKYBLUE (75 2200);
DISPLAY INVISIBLE (75 2200);
FORCEPROP 1 LAST PATH I46
J 0
(-250 2350);
DISPLAY 0.978723 (-250 2350);
PAINT WHITE (-250 2350);
DISPLAY INVISIBLE (-250 2350);
FORCEPROP 2 LAST CDS_LIB pure_quanta
J 0
(-200 2200);
DISPLAY INVISIBLE (-200 2200);
FORCEPROP 1 LAST LOCATION R127
J 0
(-425 2200);
DISPLAY 0.702128 (-425 2200);
PAINT YELLOW (-425 2200);
FORCEPROP 1 LASTPIN (-300 2200) $PN 1
J 0
(-288 2212);
DISPLAY 0.808511 (-288 2212);
PAINT WHITE (-288 2212);
FORCEPROP 1 LASTPIN (-100 2200) $PN 2
J 0
(-138 2212);
DISPLAY 0.808511 (-138 2212);
PAINT WHITE (-138 2212);
FORCEPROP 2 LAST $SEC 1
J 0
(-250 2400);
DISPLAY 0.680851 (-250 2400);
PAINT MONO (-250 2400);
DISPLAY INVISIBLE (-250 2400);
FORCEPROP 0 LAST CDS_SEC 1
J 0
(-250 2400);
DISPLAY 0.680851 (-250 2400);
PAINT MONO (-250 2400);
DISPLAY INVISIBLE (-250 2400);
FORCEADD OFFPAGE..2
R 2
(-2475 75);
FORCEPROP 2 LAST $XR3 46 
J 0
(-2729 39);
DISPLAY 0.638298 (-2729 39);
PAINT MONO (-2729 39);
FORCEPROP 2 LAST $XR2 36 
J 0
(-2909 75);
DISPLAY 0.638298 (-2909 75);
PAINT MONO (-2909 75);
FORCEPROP 2 LAST $XR1 34 
J 0
(-2819 75);
DISPLAY 0.638298 (-2819 75);
PAINT MONO (-2819 75);
FORCEPROP 2 LAST $XR0 21 
J 0
(-2729 75);
DISPLAY 0.638298 (-2729 75);
PAINT MONO (-2729 75);
FORCEPROP 2 LAST PATH I460
J 0
(-2725 125);
DISPLAY 0.680851 (-2725 125);
DISPLAY INVISIBLE (-2725 125);
FORCEPROP 1 LAST COMMENT_BODY TRUE
J 2
(-2430 -20);
DISPLAY 0.872340 (-2430 -20);
PAINT PEACH (-2430 -20);
DISPLAY INVISIBLE (-2430 -20);
FORCEPROP 1 LAST OFFPAGE TRUE
J 2
(-2800 -50);
DISPLAY 0.872340 (-2800 -50);
PAINT GREEN (-2800 -50);
DISPLAY INVISIBLE (-2800 -50);
FORCEPROP 2 LAST CDS_LIB standard
J 0
(-2475 75);
DISPLAY INVISIBLE (-2475 75);
FORCEADD OFFPAGE..3
R 2
(-2475 25);
FORCEPROP 2 LAST $XR3 46 
J 0
(-2904 -11);
DISPLAY 0.638298 (-2904 -11);
PAINT MONO (-2904 -11);
FORCEPROP 2 LAST $XR2 36 
J 0
(-2814 -11);
DISPLAY 0.638298 (-2814 -11);
PAINT MONO (-2814 -11);
FORCEPROP 2 LAST $XR1 34 
J 0
(-2904 25);
DISPLAY 0.638298 (-2904 25);
PAINT MONO (-2904 25);
FORCEPROP 2 LAST $XR0 21 
J 0
(-2814 25);
DISPLAY 0.638298 (-2814 25);
PAINT MONO (-2814 25);
FORCEPROP 2 LAST PATH I461
J 0
(-2700 75);
DISPLAY 0.680851 (-2700 75);
DISPLAY INVISIBLE (-2700 75);
FORCEPROP 1 LAST COMMENT_BODY TRUE
J 2
(-2425 -75);
DISPLAY 0.872340 (-2425 -75);
PAINT PEACH (-2425 -75);
DISPLAY INVISIBLE (-2425 -75);
FORCEPROP 1 LAST OFFPAGE TRUE
J 2
(-2800 -100);
DISPLAY 0.872340 (-2800 -100);
PAINT GREEN (-2800 -100);
DISPLAY INVISIBLE (-2800 -100);
FORCEPROP 2 LAST CDS_LIB standard
J 0
(-2475 25);
DISPLAY INVISIBLE (-2475 25);
FORCEADD TAP..1
R 2
(-75 2850);
FORCEPROP 3 LASTPIN (-25 2850) SIG_NAME M_BMC_DDR4_DQ<15>
J 0
(-15 2860);
DISPLAY 0.659574 (-15 2860);
PAINT MONO (-15 2860);
DISPLAY INVISIBLE (-15 2860);
FORCEPROP 1 LASTPIN (-25 2850) BN 15
J 2
(-13 2858);
DISPLAY 0.702128 (-13 2858);
PAINT VIOLET (-13 2858);
FORCEPROP 1 LAST PATH I47
J 2
(-73 2850);
DISPLAY 0.872340 (-73 2850);
PAINT GREEN (-73 2850);
DISPLAY INVISIBLE (-73 2850);
FORCEPROP 1 LAST HDL_TAP TRUE
J 2
(-400 2725);
DISPLAY 0.872340 (-400 2725);
DISPLAY INVISIBLE (-400 2725);
FORCEPROP 1 LAST BODY_TYPE PLUMBING
J 2
(-75 2900);
DISPLAY 0.872340 (-75 2900);
PAINT GREEN (-75 2900);
DISPLAY INVISIBLE (-75 2900);
FORCEPROP 2 LAST CDS_LIB standard
J 0
(-75 2850);
DISPLAY INVISIBLE (-75 2850);
FORCEADD Q_RES..1
(-850 1100);
FORCEPROP 1 LAST VALUE 33.2
J 0
(-750 1100);
DISPLAY 0.510638 (-750 1100);
PAINT SKYBLUE (-750 1100);
FORCEPROP 1 LAST MATERIAL CHIP
J 0
(-650 1100);
DISPLAY 0.510638 (-650 1100);
PAINT SKYBLUE (-650 1100);
FORCEPROP 1 LAST TOLERANCE 1%
J 0
(-725 1100);
DISPLAY 0.510638 (-725 1100);
PAINT SKYBLUE (-725 1100);
DISPLAY INVISIBLE (-725 1100);
FORCEPROP 1 LAST PART_NUMBER CS03322FB03
J 0
(-900 1200);
DISPLAY 0.510638 (-900 1200);
PAINT WHITE (-900 1200);
DISPLAY INVISIBLE (-900 1200);
FORCEPROP 2 LAST CDS_LIB pure_quanta
J 0
(-850 1100);
DISPLAY INVISIBLE (-850 1100);
FORCEPROP 1 LAST WATTAGE 1/16W
J 2
(-875 950);
DISPLAY 0.510638 (-875 950);
PAINT SKYBLUE (-875 950);
DISPLAY INVISIBLE (-875 950);
FORCEPROP 1 LAST PACK_TYPE 0402LF
J 0
(-600 950);
DISPLAY 0.510638 (-600 950);
PAINT SKYBLUE (-600 950);
DISPLAY INVISIBLE (-600 950);
FORCEPROP 1 LAST PATH I473
J 0
(-900 1250);
DISPLAY 0.978723 (-900 1250);
PAINT WHITE (-900 1250);
DISPLAY INVISIBLE (-900 1250);
FORCEPROP 1 LAST LOCATION R761
J 0
(-1075 1100);
DISPLAY 0.702128 (-1075 1100);
PAINT YELLOW (-1075 1100);
FORCEPROP 1 LASTPIN (-950 1100) $PN 1
J 0
(-938 1112);
DISPLAY 0.808511 (-938 1112);
PAINT WHITE (-938 1112);
FORCEPROP 1 LASTPIN (-750 1100) $PN 2
J 0
(-788 1112);
DISPLAY 0.808511 (-788 1112);
PAINT WHITE (-788 1112);
FORCEPROP 0 LAST $SEC 1
J 0
(-900 1200);
DISPLAY 0.680851 (-900 1200);
PAINT MONO (-900 1200);
DISPLAY INVISIBLE (-900 1200);
FORCEPROP 0 LAST CDS_SEC 1
J 0
(-900 1200);
DISPLAY 0.680851 (-900 1200);
DISPLAY INVISIBLE (-900 1200);
FORCEADD Q_RES..1
(-850 1050);
FORCEPROP 1 LAST MATERIAL CHIP
J 0
(-650 1050);
DISPLAY 0.510638 (-650 1050);
PAINT SKYBLUE (-650 1050);
FORCEPROP 1 LAST VALUE 33.2
J 0
(-750 1050);
DISPLAY 0.510638 (-750 1050);
PAINT SKYBLUE (-750 1050);
FORCEPROP 1 LAST TOLERANCE 1%
J 0
(-725 1050);
DISPLAY 0.510638 (-725 1050);
PAINT SKYBLUE (-725 1050);
DISPLAY INVISIBLE (-725 1050);
FORCEPROP 1 LAST PART_NUMBER CS03322FB03
J 0
(-900 1150);
DISPLAY 0.510638 (-900 1150);
PAINT WHITE (-900 1150);
DISPLAY INVISIBLE (-900 1150);
FORCEPROP 2 LAST CDS_LIB pure_quanta
J 0
(-850 1050);
DISPLAY INVISIBLE (-850 1050);
FORCEPROP 1 LAST WATTAGE 1/16W
J 2
(-875 900);
DISPLAY 0.510638 (-875 900);
PAINT SKYBLUE (-875 900);
DISPLAY INVISIBLE (-875 900);
FORCEPROP 1 LAST PACK_TYPE 0402LF
J 0
(-600 900);
DISPLAY 0.510638 (-600 900);
PAINT SKYBLUE (-600 900);
DISPLAY INVISIBLE (-600 900);
FORCEPROP 1 LAST PATH I474
J 0
(-900 1200);
DISPLAY 0.978723 (-900 1200);
PAINT WHITE (-900 1200);
DISPLAY INVISIBLE (-900 1200);
FORCEPROP 1 LAST LOCATION R762
J 0
(-1075 1050);
DISPLAY 0.702128 (-1075 1050);
PAINT YELLOW (-1075 1050);
FORCEPROP 1 LASTPIN (-950 1050) $PN 1
J 0
(-938 1062);
DISPLAY 0.808511 (-938 1062);
PAINT WHITE (-938 1062);
FORCEPROP 1 LASTPIN (-750 1050) $PN 2
J 0
(-788 1062);
DISPLAY 0.808511 (-788 1062);
PAINT WHITE (-788 1062);
FORCEPROP 0 LAST $SEC 1
J 0
(-900 1150);
DISPLAY 0.680851 (-900 1150);
PAINT MONO (-900 1150);
DISPLAY INVISIBLE (-900 1150);
FORCEPROP 0 LAST CDS_SEC 1
J 0
(-900 1150);
DISPLAY 0.680851 (-900 1150);
DISPLAY INVISIBLE (-900 1150);
FORCEADD OFFPAGE..1
(-2125 1050);
FORCEPROP 2 LAST $XR0 31 
J 0
(-2376 1050);
DISPLAY 0.638298 (-2376 1050);
PAINT MONO (-2376 1050);
FORCEPROP 2 LAST CDS_LIB standard
J 0
(-2125 1050);
DISPLAY INVISIBLE (-2125 1050);
FORCEPROP 1 LAST OFFPAGE TRUE
J 0
(-1800 925);
DISPLAY 0.872340 (-1800 925);
PAINT GREEN (-1800 925);
DISPLAY INVISIBLE (-1800 925);
FORCEPROP 1 LAST COMMENT_BODY TRUE
J 0
(-2000 950);
DISPLAY 0.872340 (-2000 950);
PAINT PEACH (-2000 950);
DISPLAY INVISIBLE (-2000 950);
FORCEPROP 2 LAST PATH I477
J 0
(-2375 1100);
DISPLAY 0.680851 (-2375 1100);
DISPLAY INVISIBLE (-2375 1100);
FORCEADD OFFPAGE..2
R 2
(-2125 1100);
FORCEPROP 2 LAST $XR0 31 
J 0
(-2379 1100);
DISPLAY 0.638298 (-2379 1100);
PAINT MONO (-2379 1100);
FORCEPROP 2 LAST CDS_LIB standard
J 0
(-2125 1100);
DISPLAY INVISIBLE (-2125 1100);
FORCEPROP 2 LAST PATH I478
J 0
(-2375 1150);
DISPLAY 0.680851 (-2375 1150);
DISPLAY INVISIBLE (-2375 1150);
FORCEPROP 1 LAST COMMENT_BODY TRUE
J 2
(-2080 1005);
DISPLAY 0.872340 (-2080 1005);
PAINT PEACH (-2080 1005);
DISPLAY INVISIBLE (-2080 1005);
FORCEPROP 1 LAST OFFPAGE TRUE
J 2
(-2450 975);
DISPLAY 0.872340 (-2450 975);
PAINT GREEN (-2450 975);
DISPLAY INVISIBLE (-2450 975);
FORCEADD TAP..1
R 2
(-75 2900);
FORCEPROP 3 LASTPIN (-25 2900) SIG_NAME M_BMC_DDR4_DQ<14>
J 0
(-15 2910);
DISPLAY 0.659574 (-15 2910);
PAINT MONO (-15 2910);
DISPLAY INVISIBLE (-15 2910);
FORCEPROP 1 LASTPIN (-25 2900) BN 14
J 2
(-13 2908);
DISPLAY 0.702128 (-13 2908);
PAINT VIOLET (-13 2908);
FORCEPROP 1 LAST PATH I48
J 2
(-73 2900);
DISPLAY 0.872340 (-73 2900);
PAINT GREEN (-73 2900);
DISPLAY INVISIBLE (-73 2900);
FORCEPROP 1 LAST HDL_TAP TRUE
J 2
(-400 2775);
DISPLAY 0.872340 (-400 2775);
DISPLAY INVISIBLE (-400 2775);
FORCEPROP 1 LAST BODY_TYPE PLUMBING
J 2
(-75 2950);
DISPLAY 0.872340 (-75 2950);
PAINT GREEN (-75 2950);
DISPLAY INVISIBLE (-75 2950);
FORCEPROP 2 LAST CDS_LIB standard
J 0
(-75 2900);
DISPLAY INVISIBLE (-75 2900);
FORCEADD OFFPAGE..3
R 2
(-2125 1700);
FORCEPROP 2 LAST $XR0 21 
J 0
(-2374 1700);
DISPLAY 0.638298 (-2374 1700);
PAINT MONO (-2374 1700);
FORCEPROP 1 LAST COMMENT_BODY TRUE
J 2
(-2075 1600);
DISPLAY 0.872340 (-2075 1600);
PAINT PEACH (-2075 1600);
DISPLAY INVISIBLE (-2075 1600);
FORCEPROP 1 LAST OFFPAGE TRUE
J 2
(-2450 1575);
DISPLAY 0.872340 (-2450 1575);
PAINT GREEN (-2450 1575);
DISPLAY INVISIBLE (-2450 1575);
FORCEPROP 2 LAST CDS_LIB standard
J 0
(-2125 1700);
DISPLAY INVISIBLE (-2125 1700);
FORCEPROP 2 LAST PATH I485
J 0
(-2400 1750);
DISPLAY 0.680851 (-2400 1750);
DISPLAY INVISIBLE (-2400 1750);
FORCEADD OFFPAGE..3
R 2
(-2125 1650);
FORCEPROP 2 LAST $XR0 21 
J 0
(-2374 1650);
DISPLAY 0.638298 (-2374 1650);
PAINT MONO (-2374 1650);
FORCEPROP 1 LAST COMMENT_BODY TRUE
J 2
(-2075 1550);
DISPLAY 0.872340 (-2075 1550);
PAINT PEACH (-2075 1550);
DISPLAY INVISIBLE (-2075 1550);
FORCEPROP 1 LAST OFFPAGE TRUE
J 2
(-2450 1525);
DISPLAY 0.872340 (-2450 1525);
PAINT GREEN (-2450 1525);
DISPLAY INVISIBLE (-2450 1525);
FORCEPROP 2 LAST CDS_LIB standard
J 0
(-2125 1650);
DISPLAY INVISIBLE (-2125 1650);
FORCEPROP 2 LAST PATH I487
J 0
(-2400 1700);
DISPLAY 0.680851 (-2400 1700);
DISPLAY INVISIBLE (-2400 1700);
FORCEADD OFFPAGE..3
R 2
(-2125 1600);
FORCEPROP 2 LAST $XR0 21 
J 0
(-2374 1600);
DISPLAY 0.638298 (-2374 1600);
PAINT MONO (-2374 1600);
FORCEPROP 1 LAST COMMENT_BODY TRUE
J 2
(-2075 1500);
DISPLAY 0.872340 (-2075 1500);
PAINT PEACH (-2075 1500);
DISPLAY INVISIBLE (-2075 1500);
FORCEPROP 1 LAST OFFPAGE TRUE
J 2
(-2450 1475);
DISPLAY 0.872340 (-2450 1475);
PAINT GREEN (-2450 1475);
DISPLAY INVISIBLE (-2450 1475);
FORCEPROP 2 LAST CDS_LIB standard
J 0
(-2125 1600);
DISPLAY INVISIBLE (-2125 1600);
FORCEPROP 2 LAST PATH I488
J 0
(-2400 1650);
DISPLAY 0.680851 (-2400 1650);
DISPLAY INVISIBLE (-2400 1650);
FORCEADD OFFPAGE..3
R 2
(-2125 1550);
FORCEPROP 2 LAST $XR0 21 
J 0
(-2374 1550);
DISPLAY 0.638298 (-2374 1550);
PAINT MONO (-2374 1550);
FORCEPROP 1 LAST COMMENT_BODY TRUE
J 2
(-2075 1450);
DISPLAY 0.872340 (-2075 1450);
PAINT PEACH (-2075 1450);
DISPLAY INVISIBLE (-2075 1450);
FORCEPROP 1 LAST OFFPAGE TRUE
J 2
(-2450 1425);
DISPLAY 0.872340 (-2450 1425);
PAINT GREEN (-2450 1425);
DISPLAY INVISIBLE (-2450 1425);
FORCEPROP 2 LAST CDS_LIB standard
J 0
(-2125 1550);
DISPLAY INVISIBLE (-2125 1550);
FORCEPROP 2 LAST PATH I489
J 0
(-2400 1600);
DISPLAY 0.680851 (-2400 1600);
DISPLAY INVISIBLE (-2400 1600);
FORCEADD TAP..1
R 2
(-75 2950);
FORCEPROP 3 LASTPIN (-25 2950) SIG_NAME M_BMC_DDR4_DQ<13>
J 0
(-15 2960);
DISPLAY 0.659574 (-15 2960);
PAINT MONO (-15 2960);
DISPLAY INVISIBLE (-15 2960);
FORCEPROP 1 LASTPIN (-25 2950) BN 13
J 2
(-13 2958);
DISPLAY 0.702128 (-13 2958);
PAINT VIOLET (-13 2958);
FORCEPROP 1 LAST PATH I49
J 2
(-73 2950);
DISPLAY 0.872340 (-73 2950);
PAINT GREEN (-73 2950);
DISPLAY INVISIBLE (-73 2950);
FORCEPROP 1 LAST HDL_TAP TRUE
J 2
(-400 2825);
DISPLAY 0.872340 (-400 2825);
DISPLAY INVISIBLE (-400 2825);
FORCEPROP 1 LAST BODY_TYPE PLUMBING
J 2
(-75 3000);
DISPLAY 0.872340 (-75 3000);
PAINT GREEN (-75 3000);
DISPLAY INVISIBLE (-75 3000);
FORCEPROP 2 LAST CDS_LIB standard
J 0
(-75 2950);
DISPLAY INVISIBLE (-75 2950);
FORCEADD OFFPAGE..3
R 2
(-2125 1500);
FORCEPROP 2 LAST $XR0 21 
J 0
(-2374 1500);
DISPLAY 0.638298 (-2374 1500);
PAINT MONO (-2374 1500);
FORCEPROP 1 LAST COMMENT_BODY TRUE
J 2
(-2075 1400);
DISPLAY 0.872340 (-2075 1400);
PAINT PEACH (-2075 1400);
DISPLAY INVISIBLE (-2075 1400);
FORCEPROP 1 LAST OFFPAGE TRUE
J 2
(-2450 1375);
DISPLAY 0.872340 (-2450 1375);
PAINT GREEN (-2450 1375);
DISPLAY INVISIBLE (-2450 1375);
FORCEPROP 2 LAST PATH I490
J 0
(-2400 1550);
DISPLAY 0.680851 (-2400 1550);
DISPLAY INVISIBLE (-2400 1550);
FORCEPROP 2 LAST CDS_LIB standard
J 0
(-2125 1500);
DISPLAY INVISIBLE (-2125 1500);
FORCEADD OFFPAGE..3
R 2
(-2125 850);
FORCEPROP 2 LAST $XR0 21 
J 0
(-2374 850);
DISPLAY 0.638298 (-2374 850);
PAINT MONO (-2374 850);
FORCEPROP 2 LAST CDS_LIB standard
J 0
(-2125 850);
DISPLAY INVISIBLE (-2125 850);
FORCEPROP 2 LAST PATH I493
J 0
(-2075 925);
DISPLAY 0.680851 (-2075 925);
DISPLAY INVISIBLE (-2075 925);
FORCEPROP 1 LAST OFFPAGE TRUE
J 2
(-2450 725);
DISPLAY 0.872340 (-2450 725);
PAINT GREEN (-2450 725);
DISPLAY INVISIBLE (-2450 725);
FORCEPROP 1 LAST COMMENT_BODY TRUE
J 2
(-2075 750);
DISPLAY 0.872340 (-2075 750);
PAINT PEACH (-2075 750);
DISPLAY INVISIBLE (-2075 750);
FORCEADD OFFPAGE..3
R 2
(-2125 900);
FORCEPROP 2 LAST $XR0 21 
J 0
(-2374 900);
DISPLAY 0.638298 (-2374 900);
PAINT MONO (-2374 900);
FORCEPROP 2 LAST CDS_LIB standard
J 0
(-2125 900);
DISPLAY INVISIBLE (-2125 900);
FORCEPROP 2 LAST PATH I494
J 0
(-2075 975);
DISPLAY 0.680851 (-2075 975);
DISPLAY INVISIBLE (-2075 975);
FORCEPROP 1 LAST OFFPAGE TRUE
J 2
(-2450 775);
DISPLAY 0.872340 (-2450 775);
PAINT GREEN (-2450 775);
DISPLAY INVISIBLE (-2450 775);
FORCEPROP 1 LAST COMMENT_BODY TRUE
J 2
(-2075 800);
DISPLAY 0.872340 (-2075 800);
PAINT PEACH (-2075 800);
DISPLAY INVISIBLE (-2075 800);
FORCEADD OFFPAGE..3
R 2
(-2125 950);
FORCEPROP 2 LAST $XR0 21 
J 0
(-2374 950);
DISPLAY 0.638298 (-2374 950);
PAINT MONO (-2374 950);
FORCEPROP 2 LAST CDS_LIB standard
J 0
(-2125 950);
DISPLAY INVISIBLE (-2125 950);
FORCEPROP 2 LAST PATH I495
J 0
(-2075 1025);
DISPLAY 0.680851 (-2075 1025);
DISPLAY INVISIBLE (-2075 1025);
FORCEPROP 1 LAST OFFPAGE TRUE
J 2
(-2450 825);
DISPLAY 0.872340 (-2450 825);
PAINT GREEN (-2450 825);
DISPLAY INVISIBLE (-2450 825);
FORCEPROP 1 LAST COMMENT_BODY TRUE
J 2
(-2075 850);
DISPLAY 0.872340 (-2075 850);
PAINT PEACH (-2075 850);
DISPLAY INVISIBLE (-2075 850);
FORCEADD OFFPAGE..3
R 2
(-2125 1000);
FORCEPROP 2 LAST $XR0 21 
J 0
(-2374 1000);
DISPLAY 0.638298 (-2374 1000);
PAINT MONO (-2374 1000);
FORCEPROP 2 LAST CDS_LIB standard
J 0
(-2125 1000);
DISPLAY INVISIBLE (-2125 1000);
FORCEPROP 2 LAST PATH I496
J 0
(-2075 1075);
DISPLAY 0.680851 (-2075 1075);
DISPLAY INVISIBLE (-2075 1075);
FORCEPROP 1 LAST OFFPAGE TRUE
J 2
(-2450 875);
DISPLAY 0.872340 (-2450 875);
PAINT GREEN (-2450 875);
DISPLAY INVISIBLE (-2450 875);
FORCEPROP 1 LAST COMMENT_BODY TRUE
J 2
(-2075 900);
DISPLAY 0.872340 (-2075 900);
PAINT PEACH (-2075 900);
DISPLAY INVISIBLE (-2075 900);
FORCEADD OFFPAGE..2
(5300 650);
FORCEPROP 2 LAST $XR0 36 
J 0
(5489 650);
DISPLAY 0.638298 (5489 650);
PAINT MONO (5489 650);
FORCEPROP 2 LAST CDS_LIB standard
J 0
(5300 650);
DISPLAY INVISIBLE (5300 650);
FORCEPROP 2 LAST PATH I499
J 0
(5475 725);
DISPLAY 0.680851 (5475 725);
DISPLAY INVISIBLE (5475 725);
FORCEPROP 1 LAST COMMENT_BODY TRUE
J 0
(5255 555);
DISPLAY 0.872340 (5255 555);
PAINT PEACH (5255 555);
DISPLAY INVISIBLE (5255 555);
FORCEPROP 1 LAST OFFPAGE TRUE
J 0
(5625 525);
DISPLAY 0.872340 (5625 525);
PAINT GREEN (5625 525);
DISPLAY INVISIBLE (5625 525);
FORCEADD UNIVERSAL_GND..1
(-1500 4675);
FORCEPROP 3 LASTPIN (-1500 4725) SIG_NAME GND\g
J 0
(-1490 4735);
DISPLAY 0.659574 (-1490 4735);
PAINT MONO (-1490 4735);
DISPLAY INVISIBLE (-1490 4735);
FORCEPROP 2 LAST CDS_LIB logical_power
J 0
(-1500 4675);
DISPLAY INVISIBLE (-1500 4675);
FORCEPROP 1 LAST HDL_POWER GND
J 1
(-1475 4600);
DISPLAY 0.702128 (-1475 4600);
PAINT GREEN (-1475 4600);
DISPLAY INVISIBLE (-1475 4600);
FORCEPROP 1 LAST PATH I50
J 0
(-1425 4675);
DISPLAY 0.872340 (-1425 4675);
PAINT AQUA (-1425 4675);
DISPLAY INVISIBLE (-1425 4675);
FORCEADD OFFPAGE..2
(5300 600);
FORCEPROP 2 LAST $XR0 36 
J 0
(5489 600);
DISPLAY 0.638298 (5489 600);
PAINT MONO (5489 600);
FORCEPROP 1 LAST COMMENT_BODY TRUE
J 0
(5255 505);
DISPLAY 0.872340 (5255 505);
PAINT PEACH (5255 505);
DISPLAY INVISIBLE (5255 505);
FORCEPROP 1 LAST OFFPAGE TRUE
J 0
(5625 475);
DISPLAY 0.872340 (5625 475);
PAINT GREEN (5625 475);
DISPLAY INVISIBLE (5625 475);
FORCEPROP 2 LAST PATH I500
J 0
(5475 675);
DISPLAY 0.680851 (5475 675);
DISPLAY INVISIBLE (5475 675);
FORCEPROP 2 LAST CDS_LIB standard
J 0
(5300 600);
DISPLAY INVISIBLE (5300 600);
FORCEADD OFFPAGE..2
R 2
(-2125 1750);
FORCEPROP 2 LAST $XR0 21 
J 0
(-2379 1750);
DISPLAY 0.638298 (-2379 1750);
PAINT MONO (-2379 1750);
FORCEPROP 1 LAST OFFPAGE TRUE
J 2
(-2450 1625);
DISPLAY 0.872340 (-2450 1625);
PAINT GREEN (-2450 1625);
DISPLAY INVISIBLE (-2450 1625);
FORCEPROP 1 LAST COMMENT_BODY TRUE
J 2
(-2080 1655);
DISPLAY 0.872340 (-2080 1655);
PAINT PEACH (-2080 1655);
DISPLAY INVISIBLE (-2080 1655);
FORCEPROP 2 LAST PATH I503
J 0
(-2075 1825);
DISPLAY 0.680851 (-2075 1825);
DISPLAY INVISIBLE (-2075 1825);
FORCEPROP 2 LAST CDS_LIB standard
J 0
(-2125 1750);
DISPLAY INVISIBLE (-2125 1750);
FORCEADD OFFPAGE..1
(-2125 1450);
FORCEPROP 2 LAST $XR0 14 
J 0
(-2376 1450);
DISPLAY 0.638298 (-2376 1450);
PAINT MONO (-2376 1450);
FORCEPROP 1 LAST COMMENT_BODY TRUE
J 0
(-2000 1350);
DISPLAY 0.872340 (-2000 1350);
PAINT PEACH (-2000 1350);
DISPLAY INVISIBLE (-2000 1350);
FORCEPROP 1 LAST OFFPAGE TRUE
J 0
(-1800 1325);
DISPLAY 0.872340 (-1800 1325);
PAINT GREEN (-1800 1325);
DISPLAY INVISIBLE (-1800 1325);
FORCEPROP 2 LAST PATH I504
J 0
(-2075 1525);
DISPLAY 0.680851 (-2075 1525);
DISPLAY INVISIBLE (-2075 1525);
FORCEPROP 2 LAST CDS_LIB standard
J 0
(-2125 1450);
DISPLAY INVISIBLE (-2125 1450);
FORCEADD OFFPAGE..1
(-2125 1400);
FORCEPROP 2 LAST $XR0 14 
J 0
(-2346 1400);
DISPLAY 0.638298 (-2346 1400);
PAINT MONO (-2346 1400);
FORCEPROP 1 LAST OFFPAGE TRUE
J 0
(-1800 1275);
DISPLAY 0.872340 (-1800 1275);
PAINT GREEN (-1800 1275);
DISPLAY INVISIBLE (-1800 1275);
FORCEPROP 1 LAST COMMENT_BODY TRUE
J 0
(-2000 1300);
DISPLAY 0.872340 (-2000 1300);
PAINT PEACH (-2000 1300);
DISPLAY INVISIBLE (-2000 1300);
FORCEPROP 2 LAST PATH I505
J 0
(-2075 1475);
DISPLAY 0.680851 (-2075 1475);
DISPLAY INVISIBLE (-2075 1475);
FORCEPROP 2 LAST CDS_LIB standard
J 0
(-2125 1400);
DISPLAY INVISIBLE (-2125 1400);
FORCEADD OFFPAGE..3
R 2
(-2125 800);
FORCEPROP 2 LAST $XR0 27 
J 0
(-2374 800);
DISPLAY 0.638298 (-2374 800);
PAINT MONO (-2374 800);
FORCEPROP 2 LAST CDS_LIB standard
J 0
(-2125 800);
DISPLAY INVISIBLE (-2125 800);
FORCEPROP 2 LAST PATH I506
J 0
(-2075 875);
DISPLAY 0.680851 (-2075 875);
DISPLAY INVISIBLE (-2075 875);
FORCEPROP 1 LAST OFFPAGE TRUE
J 2
(-2450 675);
DISPLAY 0.872340 (-2450 675);
PAINT GREEN (-2450 675);
DISPLAY INVISIBLE (-2450 675);
FORCEPROP 1 LAST COMMENT_BODY TRUE
J 2
(-2075 700);
DISPLAY 0.872340 (-2075 700);
PAINT PEACH (-2075 700);
DISPLAY INVISIBLE (-2075 700);
FORCEADD OFFPAGE..4
(5875 -100);
FORCEPROP 2 LAST $XR1 34 
J 0
(6151 -100);
DISPLAY 0.638298 (6151 -100);
PAINT MONO (6151 -100);
FORCEPROP 2 LAST $XR0 46 
J 0
(6061 -100);
DISPLAY 0.638298 (6061 -100);
PAINT MONO (6061 -100);
FORCEPROP 2 LAST PATH I507
J 0
(6175 -50);
DISPLAY 0.680851 (6175 -50);
DISPLAY INVISIBLE (6175 -50);
FORCEPROP 2 LAST CDS_LIB standard
J 0
(5875 -100);
DISPLAY INVISIBLE (5875 -100);
FORCEPROP 1 LAST OFFPAGE TRUE
J 0
(6200 -225);
DISPLAY 1.574468 (6200 -225);
PAINT GREEN (6200 -225);
DISPLAY INVISIBLE (6200 -225);
FORCEPROP 1 LAST COMMENT_BODY TRUE
J 0
(5850 -200);
DISPLAY 1.574468 (5850 -200);
PAINT PEACH (5850 -200);
DISPLAY INVISIBLE (5850 -200);
FORCEADD Q_RES..1
(-575 3800);
FORCEPROP 1 LAST PART_NUMBER CS41002FB09
J 0
(-775 3850);
DISPLAY 0.510638 (-775 3850);
PAINT WHITE (-775 3850);
FORCEPROP 1 LAST VALUE 100K
J 2
(-350 3800);
DISPLAY 0.510638 (-350 3800);
PAINT SKYBLUE (-350 3800);
FORCEPROP 1 LAST MATERIAL CHIP
J 0
(-750 3800);
DISPLAY 0.510638 (-750 3800);
PAINT SKYBLUE (-750 3800);
FORCEPROP 1 LAST PATH I508
J 0
(-625 3950);
DISPLAY 0.978723 (-625 3950);
PAINT WHITE (-625 3950);
DISPLAY INVISIBLE (-625 3950);
FORCEPROP 2 LAST CDS_LIB pure_quanta
J 0
(-575 3800);
DISPLAY INVISIBLE (-575 3800);
FORCEPROP 1 LAST PACK_TYPE 0402LF
J 0
(-625 3875);
DISPLAY 0.510638 (-625 3875);
PAINT SKYBLUE (-625 3875);
DISPLAY INVISIBLE (-625 3875);
FORCEPROP 1 LAST WATTAGE 1/16W
J 2
(-275 3875);
DISPLAY 0.510638 (-275 3875);
PAINT SKYBLUE (-275 3875);
DISPLAY INVISIBLE (-275 3875);
FORCEPROP 1 LAST TOLERANCE 1%
J 0
(-250 3875);
DISPLAY 0.510638 (-250 3875);
PAINT SKYBLUE (-250 3875);
DISPLAY INVISIBLE (-250 3875);
FORCEPROP 1 LAST $LOCATION R387
J 0
(-875 3800);
DISPLAY 0.702128 (-875 3800);
PAINT YELLOW (-875 3800);
FORCEPROP 1 LASTPIN (-675 3800) $PN 1
J 0
(-663 3812);
DISPLAY 0.787234 (-663 3812);
PAINT MONO (-663 3812);
FORCEPROP 1 LASTPIN (-475 3800) $PN 2
J 0
(-513 3812);
DISPLAY 0.787234 (-513 3812);
PAINT MONO (-513 3812);
FORCEPROP 0 LAST CDS_LOCATION R387
J 0
(-775 3875);
DISPLAY 0.680851 (-775 3875);
DISPLAY INVISIBLE (-775 3875);
FORCEPROP 0 LAST $SEC 1
J 0
(-775 3875);
DISPLAY 0.680851 (-775 3875);
PAINT MONO (-775 3875);
DISPLAY INVISIBLE (-775 3875);
FORCEPROP 0 LAST CDS_SEC 1
J 0
(-775 3875);
DISPLAY 0.680851 (-775 3875);
DISPLAY INVISIBLE (-775 3875);
FORCEADD UNIVERSAL_GND..1
(-1550 3600);
FORCEPROP 3 LASTPIN (-1550 3650) SIG_NAME GND\g
J 0
(-1540 3660);
DISPLAY 0.659574 (-1540 3660);
PAINT MONO (-1540 3660);
DISPLAY INVISIBLE (-1540 3660);
FORCEPROP 1 LAST HDL_POWER GND
J 1
(-1525 3525);
DISPLAY 0.702128 (-1525 3525);
PAINT GREEN (-1525 3525);
DISPLAY INVISIBLE (-1525 3525);
FORCEPROP 1 LAST PATH I509
J 0
(-1475 3600);
DISPLAY 0.872340 (-1475 3600);
PAINT AQUA (-1475 3600);
DISPLAY INVISIBLE (-1475 3600);
FORCEPROP 2 LAST CDS_LIB logical_power
J 0
(-1550 3600);
DISPLAY INVISIBLE (-1550 3600);
FORCEADD OFFPAGE..3
R 2
(-1000 3650);
FORCEPROP 2 LAST $XR0 20 
J 0
(-1249 3650);
DISPLAY 0.638298 (-1249 3650);
PAINT MONO (-1249 3650);
FORCEPROP 2 LAST PATH I51
J 0
(-1225 3700);
DISPLAY 1.021277 (-1225 3700);
DISPLAY INVISIBLE (-1225 3700);
FORCEPROP 1 LAST COMMENT_BODY TRUE
J 2
(-950 3550);
DISPLAY 0.872340 (-950 3550);
PAINT PEACH (-950 3550);
DISPLAY INVISIBLE (-950 3550);
FORCEPROP 1 LAST OFFPAGE TRUE
J 2
(-1325 3525);
DISPLAY 0.872340 (-1325 3525);
PAINT GREEN (-1325 3525);
DISPLAY INVISIBLE (-1325 3525);
FORCEPROP 2 LAST CDS_LIB standard
J 0
(-1000 3650);
DISPLAY INVISIBLE (-1000 3650);
FORCEADD Q_RES..1
(-1400 75);
FORCEPROP 1 LAST VALUE 200
J 2
(-1200 75);
DISPLAY 0.510638 (-1200 75);
PAINT SKYBLUE (-1200 75);
FORCEPROP 1 LAST MATERIAL CHIP
J 0
(-1125 75);
DISPLAY 0.510638 (-1125 75);
PAINT SKYBLUE (-1125 75);
FORCEPROP 1 LAST PART_NUMBER CS12002FB06
J 0
(-1450 175);
DISPLAY 0.638298 (-1450 175);
FORCEPROP 1 LAST PACK_TYPE 0402LF
J 0
(-1150 -75);
DISPLAY 0.638298 (-1150 -75);
DISPLAY INVISIBLE (-1150 -75);
FORCEPROP 1 LAST WATTAGE 1/16W
J 2
(-1425 -75);
DISPLAY 0.638298 (-1425 -75);
DISPLAY INVISIBLE (-1425 -75);
FORCEPROP 1 LAST TOLERANCE 1%
J 0
(-1400 -25);
DISPLAY 0.638298 (-1400 -25);
DISPLAY INVISIBLE (-1400 -25);
FORCEPROP 1 LAST PATH I510
J 0
(-1450 225);
DISPLAY 0.978723 (-1450 225);
PAINT WHITE (-1450 225);
DISPLAY INVISIBLE (-1450 225);
FORCEPROP 2 LAST CDS_LIB pure_quanta
J 0
(-1400 75);
DISPLAY INVISIBLE (-1400 75);
FORCEPROP 1 LAST LOCATION R879
J 0
(-1675 75);
DISPLAY 0.808511 (-1675 75);
PAINT YELLOW (-1675 75);
FORCEPROP 1 LASTPIN (-1500 75) $PN 1
J 0
(-1488 87);
DISPLAY 0.787234 (-1488 87);
PAINT MONO (-1488 87);
FORCEPROP 1 LASTPIN (-1300 75) $PN 2
J 0
(-1338 87);
DISPLAY 0.787234 (-1338 87);
PAINT MONO (-1338 87);
FORCEPROP 0 LAST $SEC 1
J 0
(-1450 225);
DISPLAY 0.680851 (-1450 225);
PAINT MONO (-1450 225);
DISPLAY INVISIBLE (-1450 225);
FORCEPROP 0 LAST CDS_SEC 1
J 0
(-1450 225);
DISPLAY 0.680851 (-1450 225);
DISPLAY INVISIBLE (-1450 225);
FORCEADD Q_RES..1
(4125 1500);
FORCEPROP 1 LAST VALUE 33.2
J 0
(4250 1500);
DISPLAY 0.510638 (4250 1500);
PAINT SKYBLUE (4250 1500);
FORCEPROP 1 LAST MATERIAL CHIP
J 2
(4500 1500);
DISPLAY 0.510638 (4500 1500);
PAINT SKYBLUE (4500 1500);
FORCEPROP 1 LAST TOLERANCE 1%
J 0
(4250 1500);
DISPLAY 0.510638 (4250 1500);
PAINT SKYBLUE (4250 1500);
DISPLAY INVISIBLE (4250 1500);
FORCEPROP 1 LAST PART_NUMBER CS03322FB03
J 0
(4075 1600);
DISPLAY 0.510638 (4075 1600);
PAINT WHITE (4075 1600);
DISPLAY INVISIBLE (4075 1600);
FORCEPROP 2 LAST CDS_LIB pure_quanta
J 0
(4125 1500);
DISPLAY INVISIBLE (4125 1500);
FORCEPROP 1 LAST WATTAGE 1/16W
J 2
(4100 1350);
DISPLAY 0.510638 (4100 1350);
PAINT SKYBLUE (4100 1350);
DISPLAY INVISIBLE (4100 1350);
FORCEPROP 1 LAST PACK_TYPE 0402LF
J 0
(4375 1350);
DISPLAY 0.510638 (4375 1350);
PAINT SKYBLUE (4375 1350);
DISPLAY INVISIBLE (4375 1350);
FORCEPROP 1 LAST PATH I512
J 0
(4075 1650);
DISPLAY 0.978723 (4075 1650);
PAINT WHITE (4075 1650);
DISPLAY INVISIBLE (4075 1650);
FORCEPROP 1 LAST LOCATION R139
J 2
(3950 1500);
DISPLAY 0.702128 (3950 1500);
PAINT YELLOW (3950 1500);
FORCEPROP 0 LAST $SEC 1
J 0
(3875 1550);
DISPLAY 0.680851 (3875 1550);
PAINT MONO (3875 1550);
DISPLAY INVISIBLE (3875 1550);
FORCEPROP 0 LAST CDS_SEC 1
J 0
(3875 1550);
DISPLAY 1.021277 (3875 1550);
DISPLAY INVISIBLE (3875 1550);
FORCEPROP 1 LASTPIN (4025 1500) $PN 1
J 0
(4037 1512);
DISPLAY 0.808511 (4037 1512);
PAINT WHITE (4037 1512);
DISPLAY INVISIBLE (4037 1512);
FORCEPROP 1 LASTPIN (4225 1500) $PN 2
J 0
(4187 1512);
DISPLAY 0.808511 (4187 1512);
PAINT WHITE (4187 1512);
DISPLAY INVISIBLE (4187 1512);
FORCEADD Q_RES..1
(4125 1550);
FORCEPROP 1 LAST MATERIAL CHIP
J 0
(4400 1550);
DISPLAY 0.510638 (4400 1550);
PAINT SKYBLUE (4400 1550);
FORCEPROP 1 LAST VALUE 40.2
J 2
(4350 1550);
DISPLAY 0.510638 (4350 1550);
PAINT SKYBLUE (4350 1550);
FORCEPROP 2 LAST CDS_LIB pure_quanta
J 0
(4125 1550);
DISPLAY INVISIBLE (4125 1550);
FORCEPROP 1 LAST TOLERANCE 1%
J 0
(4125 1450);
DISPLAY 0.978723 (4125 1450);
DISPLAY INVISIBLE (4125 1450);
FORCEPROP 1 LAST PACK_TYPE 0402LF
J 0
(4375 1400);
DISPLAY 0.978723 (4375 1400);
DISPLAY INVISIBLE (4375 1400);
FORCEPROP 1 LAST WATTAGE 1/16W
J 2
(4100 1400);
DISPLAY 0.978723 (4100 1400);
DISPLAY INVISIBLE (4100 1400);
FORCEPROP 1 LAST PATH I513
J 0
(4075 1700);
DISPLAY 0.978723 (4075 1700);
PAINT WHITE (4075 1700);
DISPLAY INVISIBLE (4075 1700);
FORCEPROP 1 LAST PART_NUMBER CS04022FB28
J 0
(3975 1450);
DISPLAY 0.638298 (3975 1450);
DISPLAY INVISIBLE (3975 1450);
FORCEPROP 1 LAST LOCATION R138
J 0
(3850 1550);
DISPLAY 0.638298 (3850 1550);
PAINT YELLOW (3850 1550);
FORCEPROP 1 LASTPIN (4025 1550) $PN 1
J 0
(4037 1562);
DISPLAY 0.787234 (4037 1562);
PAINT MONO (4037 1562);
FORCEPROP 1 LASTPIN (4225 1550) $PN 2
J 0
(4187 1562);
DISPLAY 0.787234 (4187 1562);
PAINT MONO (4187 1562);
FORCEPROP 0 LAST $SEC 1
J 0
(3850 1600);
DISPLAY 0.680851 (3850 1600);
PAINT MONO (3850 1600);
DISPLAY INVISIBLE (3850 1600);
FORCEPROP 0 LAST CDS_SEC 1
J 0
(3850 1600);
DISPLAY 0.680851 (3850 1600);
DISPLAY INVISIBLE (3850 1600);
FORCEADD OFFPAGE..1
(-1175 4600);
FORCEPROP 2 LAST $XR2 12 
J 0
(-1606 4600);
DISPLAY 0.638298 (-1606 4600);
PAINT MONO (-1606 4600);
FORCEPROP 2 LAST $XR0 10 
J 0
(-1426 4600);
DISPLAY 0.638298 (-1426 4600);
PAINT MONO (-1426 4600);
FORCEPROP 2 LAST $XR5 46 
J 0
(-1876 4600);
DISPLAY 0.638298 (-1876 4600);
PAINT MONO (-1876 4600);
FORCEPROP 2 LAST $XR4 34 
J 0
(-1786 4600);
DISPLAY 0.638298 (-1786 4600);
PAINT MONO (-1786 4600);
FORCEPROP 2 LAST $XR3 28 
J 0
(-1696 4600);
DISPLAY 0.638298 (-1696 4600);
PAINT MONO (-1696 4600);
FORCEPROP 2 LAST $XR1 11 
J 0
(-1516 4600);
DISPLAY 0.638298 (-1516 4600);
PAINT MONO (-1516 4600);
FORCEPROP 2 LAST PATH I52
J 0
(-1375 4650);
DISPLAY 1.021277 (-1375 4650);
DISPLAY INVISIBLE (-1375 4650);
FORCEPROP 1 LAST COMMENT_BODY TRUE
J 0
(-1050 4500);
DISPLAY 0.872340 (-1050 4500);
PAINT PEACH (-1050 4500);
DISPLAY INVISIBLE (-1050 4500);
FORCEPROP 1 LAST OFFPAGE TRUE
J 0
(-850 4475);
DISPLAY 0.872340 (-850 4475);
PAINT GREEN (-850 4475);
DISPLAY INVISIBLE (-850 4475);
FORCEPROP 2 LAST CDS_LIB standard
J 0
(-1175 4600);
DISPLAY INVISIBLE (-1175 4600);
FORCEADD Q_RES..1
(-1150 4800);
FORCEPROP 1 LAST TOLERANCE 1%
J 0
(-825 4875);
DISPLAY 0.510638 (-825 4875);
PAINT SKYBLUE (-825 4875);
FORCEPROP 1 LAST PACK_TYPE 0402LF
J 0
(-1200 4875);
DISPLAY 0.510638 (-1200 4875);
PAINT SKYBLUE (-1200 4875);
FORCEPROP 1 LAST WATTAGE 1/16W
J 2
(-850 4875);
DISPLAY 0.510638 (-850 4875);
PAINT SKYBLUE (-850 4875);
FORCEPROP 1 LAST VALUE 100K
J 2
(-925 4800);
DISPLAY 0.510638 (-925 4800);
PAINT SKYBLUE (-925 4800);
FORCEPROP 1 LAST PART_NUMBER CS41002FB09
J 0
(-1350 4925);
DISPLAY 0.510638 (-1350 4925);
PAINT WHITE (-1350 4925);
FORCEPROP 1 LAST MATERIAL CHIP
J 0
(-1350 4875);
DISPLAY 0.510638 (-1350 4875);
PAINT SKYBLUE (-1350 4875);
FORCEPROP 2 LAST CDS_LIB pure_quanta
J 0
(-1150 4800);
DISPLAY INVISIBLE (-1150 4800);
FORCEPROP 1 LAST PATH I53
J 0
(-1200 4950);
DISPLAY 0.978723 (-1200 4950);
PAINT WHITE (-1200 4950);
DISPLAY INVISIBLE (-1200 4950);
FORCEPROP 1 LAST LOCATION R118
J 0
(-1450 4800);
DISPLAY 0.702128 (-1450 4800);
PAINT YELLOW (-1450 4800);
FORCEPROP 1 LASTPIN (-1250 4800) $PN 1
J 0
(-1238 4812);
DISPLAY 0.808511 (-1238 4812);
PAINT WHITE (-1238 4812);
FORCEPROP 1 LASTPIN (-1050 4800) $PN 2
J 0
(-1088 4812);
DISPLAY 0.808511 (-1088 4812);
PAINT WHITE (-1088 4812);
FORCEPROP 2 LAST $SEC 1
J 0
(-1200 5000);
DISPLAY 0.680851 (-1200 5000);
PAINT MONO (-1200 5000);
DISPLAY INVISIBLE (-1200 5000);
FORCEPROP 0 LAST CDS_SEC 1
J 0
(-1200 5000);
DISPLAY 0.680851 (-1200 5000);
PAINT MONO (-1200 5000);
DISPLAY INVISIBLE (-1200 5000);
FORCEADD OFFPAGE..1
(-425 4300);
FORCEPROP 2 LAST $XR0 10 
J 0
(-646 4300);
DISPLAY 0.638298 (-646 4300);
PAINT MONO (-646 4300);
FORCEPROP 2 LAST CDS_LIB standard
J 0
(-425 4300);
DISPLAY INVISIBLE (-425 4300);
FORCEPROP 2 LAST PATH I54
J 0
(-625 4350);
DISPLAY 1.021277 (-625 4350);
DISPLAY INVISIBLE (-625 4350);
FORCEPROP 1 LAST COMMENT_BODY TRUE
J 0
(-300 4200);
DISPLAY 0.872340 (-300 4200);
PAINT PEACH (-300 4200);
DISPLAY INVISIBLE (-300 4200);
FORCEPROP 1 LAST OFFPAGE TRUE
J 0
(-100 4175);
DISPLAY 0.872340 (-100 4175);
PAINT GREEN (-100 4175);
DISPLAY INVISIBLE (-100 4175);
FORCEADD OFFPAGE..1
(-425 4350);
FORCEPROP 2 LAST $XR0 10 
J 0
(-646 4350);
DISPLAY 0.638298 (-646 4350);
PAINT MONO (-646 4350);
FORCEPROP 2 LAST CDS_LIB standard
J 0
(-425 4350);
DISPLAY INVISIBLE (-425 4350);
FORCEPROP 2 LAST PATH I55
J 0
(-625 4400);
DISPLAY 1.021277 (-625 4400);
DISPLAY INVISIBLE (-625 4400);
FORCEPROP 1 LAST COMMENT_BODY TRUE
J 0
(-300 4250);
DISPLAY 0.872340 (-300 4250);
PAINT PEACH (-300 4250);
DISPLAY INVISIBLE (-300 4250);
FORCEPROP 1 LAST OFFPAGE TRUE
J 0
(-100 4225);
DISPLAY 0.872340 (-100 4225);
PAINT GREEN (-100 4225);
DISPLAY INVISIBLE (-100 4225);
FORCEADD OFFPAGE..1
(-425 4450);
FORCEPROP 2 LAST $XR0 10 
J 0
(-646 4450);
DISPLAY 0.638298 (-646 4450);
PAINT MONO (-646 4450);
FORCEPROP 1 LAST OFFPAGE TRUE
J 0
(-100 4325);
DISPLAY 0.872340 (-100 4325);
PAINT GREEN (-100 4325);
DISPLAY INVISIBLE (-100 4325);
FORCEPROP 1 LAST COMMENT_BODY TRUE
J 0
(-300 4350);
DISPLAY 0.872340 (-300 4350);
PAINT PEACH (-300 4350);
DISPLAY INVISIBLE (-300 4350);
FORCEPROP 2 LAST PATH I56
J 0
(-600 4500);
DISPLAY 1.021277 (-600 4500);
DISPLAY INVISIBLE (-600 4500);
FORCEPROP 2 LAST CDS_LIB standard
J 0
(-425 4450);
DISPLAY INVISIBLE (-425 4450);
FORCEADD OFFPAGE..1
(-425 4500);
FORCEPROP 2 LAST $XR0 10 
J 0
(-646 4500);
DISPLAY 0.638298 (-646 4500);
PAINT MONO (-646 4500);
FORCEPROP 1 LAST OFFPAGE TRUE
J 0
(-100 4375);
DISPLAY 0.872340 (-100 4375);
PAINT GREEN (-100 4375);
DISPLAY INVISIBLE (-100 4375);
FORCEPROP 1 LAST COMMENT_BODY TRUE
J 0
(-300 4400);
DISPLAY 0.872340 (-300 4400);
PAINT PEACH (-300 4400);
DISPLAY INVISIBLE (-300 4400);
FORCEPROP 2 LAST PATH I57
J 0
(-600 4550);
DISPLAY 1.021277 (-600 4550);
DISPLAY INVISIBLE (-600 4550);
FORCEPROP 2 LAST CDS_LIB standard
J 0
(-425 4500);
DISPLAY INVISIBLE (-425 4500);
FORCEADD TAP..1
R 2
(-75 3050);
FORCEPROP 3 LASTPIN (-25 3050) SIG_NAME M_BMC_DDR4_DQ<11>
J 0
(-15 3060);
DISPLAY 0.659574 (-15 3060);
PAINT MONO (-15 3060);
DISPLAY INVISIBLE (-15 3060);
FORCEPROP 1 LASTPIN (-25 3050) BN 11
J 2
(-13 3058);
DISPLAY 0.702128 (-13 3058);
PAINT VIOLET (-13 3058);
FORCEPROP 1 LAST PATH I58
J 2
(-73 3050);
DISPLAY 0.872340 (-73 3050);
PAINT GREEN (-73 3050);
DISPLAY INVISIBLE (-73 3050);
FORCEPROP 1 LAST HDL_TAP TRUE
J 2
(-400 2925);
DISPLAY 0.872340 (-400 2925);
DISPLAY INVISIBLE (-400 2925);
FORCEPROP 1 LAST BODY_TYPE PLUMBING
J 2
(-75 3100);
DISPLAY 0.872340 (-75 3100);
PAINT GREEN (-75 3100);
DISPLAY INVISIBLE (-75 3100);
FORCEPROP 2 LAST CDS_LIB standard
J 0
(-75 3050);
DISPLAY INVISIBLE (-75 3050);
FORCEADD TAP..1
R 2
(-75 3000);
FORCEPROP 3 LASTPIN (-25 3000) SIG_NAME M_BMC_DDR4_DQ<12>
J 0
(-15 3010);
DISPLAY 0.659574 (-15 3010);
PAINT MONO (-15 3010);
DISPLAY INVISIBLE (-15 3010);
FORCEPROP 1 LASTPIN (-25 3000) BN 12
J 2
(-13 3008);
DISPLAY 0.702128 (-13 3008);
PAINT VIOLET (-13 3008);
FORCEPROP 1 LAST PATH I59
J 2
(-73 3000);
DISPLAY 0.872340 (-73 3000);
PAINT GREEN (-73 3000);
DISPLAY INVISIBLE (-73 3000);
FORCEPROP 1 LAST HDL_TAP TRUE
J 2
(-400 2875);
DISPLAY 0.872340 (-400 2875);
DISPLAY INVISIBLE (-400 2875);
FORCEPROP 1 LAST BODY_TYPE PLUMBING
J 2
(-75 3050);
DISPLAY 0.872340 (-75 3050);
PAINT GREEN (-75 3050);
DISPLAY INVISIBLE (-75 3050);
FORCEPROP 2 LAST CDS_LIB standard
J 0
(-75 3000);
DISPLAY INVISIBLE (-75 3000);
FORCEADD TAP..1
R 2
(-75 3100);
FORCEPROP 3 LASTPIN (-25 3100) SIG_NAME M_BMC_DDR4_DQ<10>
J 0
(-15 3110);
DISPLAY 0.659574 (-15 3110);
PAINT MONO (-15 3110);
DISPLAY INVISIBLE (-15 3110);
FORCEPROP 1 LASTPIN (-25 3100) BN 10
J 2
(-13 3108);
DISPLAY 0.702128 (-13 3108);
PAINT VIOLET (-13 3108);
FORCEPROP 1 LAST PATH I60
J 2
(-73 3100);
DISPLAY 0.872340 (-73 3100);
PAINT GREEN (-73 3100);
DISPLAY INVISIBLE (-73 3100);
FORCEPROP 1 LAST HDL_TAP TRUE
J 2
(-400 2975);
DISPLAY 0.872340 (-400 2975);
DISPLAY INVISIBLE (-400 2975);
FORCEPROP 1 LAST BODY_TYPE PLUMBING
J 2
(-75 3150);
DISPLAY 0.872340 (-75 3150);
PAINT GREEN (-75 3150);
DISPLAY INVISIBLE (-75 3150);
FORCEPROP 2 LAST CDS_LIB standard
J 0
(-75 3100);
DISPLAY INVISIBLE (-75 3100);
FORCEADD TAP..1
R 2
(-75 3150);
FORCEPROP 3 LASTPIN (-25 3150) SIG_NAME M_BMC_DDR4_DQ<9>
J 0
(-15 3160);
DISPLAY 0.659574 (-15 3160);
PAINT MONO (-15 3160);
DISPLAY INVISIBLE (-15 3160);
FORCEPROP 1 LASTPIN (-25 3150) BN 9
J 2
(-13 3158);
DISPLAY 0.702128 (-13 3158);
PAINT VIOLET (-13 3158);
FORCEPROP 1 LAST PATH I61
J 2
(-73 3150);
DISPLAY 0.872340 (-73 3150);
PAINT GREEN (-73 3150);
DISPLAY INVISIBLE (-73 3150);
FORCEPROP 1 LAST HDL_TAP TRUE
J 2
(-400 3025);
DISPLAY 0.872340 (-400 3025);
DISPLAY INVISIBLE (-400 3025);
FORCEPROP 1 LAST BODY_TYPE PLUMBING
J 2
(-75 3200);
DISPLAY 0.872340 (-75 3200);
PAINT GREEN (-75 3200);
DISPLAY INVISIBLE (-75 3200);
FORCEPROP 2 LAST CDS_LIB standard
J 0
(-75 3150);
DISPLAY INVISIBLE (-75 3150);
FORCEADD TAP..1
R 2
(-75 3200);
FORCEPROP 3 LASTPIN (-25 3200) SIG_NAME M_BMC_DDR4_DQ<8>
J 0
(-15 3210);
DISPLAY 0.659574 (-15 3210);
PAINT MONO (-15 3210);
DISPLAY INVISIBLE (-15 3210);
FORCEPROP 1 LASTPIN (-25 3200) BN 8
J 2
(-13 3208);
DISPLAY 0.702128 (-13 3208);
PAINT VIOLET (-13 3208);
FORCEPROP 1 LAST PATH I62
J 2
(-73 3200);
DISPLAY 0.872340 (-73 3200);
PAINT GREEN (-73 3200);
DISPLAY INVISIBLE (-73 3200);
FORCEPROP 1 LAST HDL_TAP TRUE
J 2
(-400 3075);
DISPLAY 0.872340 (-400 3075);
DISPLAY INVISIBLE (-400 3075);
FORCEPROP 1 LAST BODY_TYPE PLUMBING
J 2
(-75 3250);
DISPLAY 0.872340 (-75 3250);
PAINT GREEN (-75 3250);
DISPLAY INVISIBLE (-75 3250);
FORCEPROP 2 LAST CDS_LIB standard
J 0
(-75 3200);
DISPLAY INVISIBLE (-75 3200);
FORCEADD TAP..1
R 2
(-75 3250);
FORCEPROP 3 LASTPIN (-25 3250) SIG_NAME M_BMC_DDR4_DQ<7>
J 0
(-15 3260);
DISPLAY 0.659574 (-15 3260);
PAINT MONO (-15 3260);
DISPLAY INVISIBLE (-15 3260);
FORCEPROP 1 LASTPIN (-25 3250) BN 7
J 2
(-13 3258);
DISPLAY 0.702128 (-13 3258);
PAINT VIOLET (-13 3258);
FORCEPROP 1 LAST PATH I63
J 2
(-73 3250);
DISPLAY 0.872340 (-73 3250);
PAINT GREEN (-73 3250);
DISPLAY INVISIBLE (-73 3250);
FORCEPROP 1 LAST HDL_TAP TRUE
J 2
(-400 3125);
DISPLAY 0.872340 (-400 3125);
DISPLAY INVISIBLE (-400 3125);
FORCEPROP 1 LAST BODY_TYPE PLUMBING
J 2
(-75 3300);
DISPLAY 0.872340 (-75 3300);
PAINT GREEN (-75 3300);
DISPLAY INVISIBLE (-75 3300);
FORCEPROP 2 LAST CDS_LIB standard
J 0
(-75 3250);
DISPLAY INVISIBLE (-75 3250);
FORCEADD TAP..1
R 2
(-75 3300);
FORCEPROP 3 LASTPIN (-25 3300) SIG_NAME M_BMC_DDR4_DQ<6>
J 0
(-15 3310);
DISPLAY 0.659574 (-15 3310);
PAINT MONO (-15 3310);
DISPLAY INVISIBLE (-15 3310);
FORCEPROP 1 LASTPIN (-25 3300) BN 6
J 2
(-13 3308);
DISPLAY 0.702128 (-13 3308);
PAINT VIOLET (-13 3308);
FORCEPROP 1 LAST PATH I64
J 2
(-73 3300);
DISPLAY 0.872340 (-73 3300);
PAINT GREEN (-73 3300);
DISPLAY INVISIBLE (-73 3300);
FORCEPROP 1 LAST HDL_TAP TRUE
J 2
(-400 3175);
DISPLAY 0.872340 (-400 3175);
DISPLAY INVISIBLE (-400 3175);
FORCEPROP 1 LAST BODY_TYPE PLUMBING
J 2
(-75 3350);
DISPLAY 0.872340 (-75 3350);
PAINT GREEN (-75 3350);
DISPLAY INVISIBLE (-75 3350);
FORCEPROP 2 LAST CDS_LIB standard
J 0
(-75 3300);
DISPLAY INVISIBLE (-75 3300);
FORCEADD TAP..1
R 2
(-75 3350);
FORCEPROP 3 LASTPIN (-25 3350) SIG_NAME M_BMC_DDR4_DQ<5>
J 0
(-15 3360);
DISPLAY 0.659574 (-15 3360);
PAINT MONO (-15 3360);
DISPLAY INVISIBLE (-15 3360);
FORCEPROP 1 LASTPIN (-25 3350) BN 5
J 2
(-13 3358);
DISPLAY 0.702128 (-13 3358);
PAINT VIOLET (-13 3358);
FORCEPROP 1 LAST PATH I65
J 2
(-73 3350);
DISPLAY 0.872340 (-73 3350);
PAINT GREEN (-73 3350);
DISPLAY INVISIBLE (-73 3350);
FORCEPROP 1 LAST HDL_TAP TRUE
J 2
(-400 3225);
DISPLAY 0.872340 (-400 3225);
DISPLAY INVISIBLE (-400 3225);
FORCEPROP 1 LAST BODY_TYPE PLUMBING
J 2
(-75 3400);
DISPLAY 0.872340 (-75 3400);
PAINT GREEN (-75 3400);
DISPLAY INVISIBLE (-75 3400);
FORCEPROP 2 LAST CDS_LIB standard
J 0
(-75 3350);
DISPLAY INVISIBLE (-75 3350);
FORCEADD TAP..1
R 2
(-75 3400);
FORCEPROP 3 LASTPIN (-25 3400) SIG_NAME M_BMC_DDR4_DQ<4>
J 0
(-15 3410);
DISPLAY 0.659574 (-15 3410);
PAINT MONO (-15 3410);
DISPLAY INVISIBLE (-15 3410);
FORCEPROP 1 LASTPIN (-25 3400) BN 4
J 2
(-13 3408);
DISPLAY 0.702128 (-13 3408);
PAINT VIOLET (-13 3408);
FORCEPROP 1 LAST PATH I66
J 2
(-73 3400);
DISPLAY 0.872340 (-73 3400);
PAINT GREEN (-73 3400);
DISPLAY INVISIBLE (-73 3400);
FORCEPROP 1 LAST HDL_TAP TRUE
J 2
(-400 3275);
DISPLAY 0.872340 (-400 3275);
DISPLAY INVISIBLE (-400 3275);
FORCEPROP 1 LAST BODY_TYPE PLUMBING
J 2
(-75 3450);
DISPLAY 0.872340 (-75 3450);
PAINT GREEN (-75 3450);
DISPLAY INVISIBLE (-75 3450);
FORCEPROP 2 LAST CDS_LIB standard
J 0
(-75 3400);
DISPLAY INVISIBLE (-75 3400);
FORCEADD TAP..1
R 2
(-75 3450);
FORCEPROP 3 LASTPIN (-25 3450) SIG_NAME M_BMC_DDR4_DQ<3>
J 0
(-15 3460);
DISPLAY 0.659574 (-15 3460);
PAINT MONO (-15 3460);
DISPLAY INVISIBLE (-15 3460);
FORCEPROP 1 LASTPIN (-25 3450) BN 3
J 2
(-13 3458);
DISPLAY 0.702128 (-13 3458);
PAINT VIOLET (-13 3458);
FORCEPROP 1 LAST PATH I67
J 2
(-73 3450);
DISPLAY 0.872340 (-73 3450);
PAINT GREEN (-73 3450);
DISPLAY INVISIBLE (-73 3450);
FORCEPROP 1 LAST HDL_TAP TRUE
J 2
(-400 3325);
DISPLAY 0.872340 (-400 3325);
DISPLAY INVISIBLE (-400 3325);
FORCEPROP 1 LAST BODY_TYPE PLUMBING
J 2
(-75 3500);
DISPLAY 0.872340 (-75 3500);
PAINT GREEN (-75 3500);
DISPLAY INVISIBLE (-75 3500);
FORCEPROP 2 LAST CDS_LIB standard
J 0
(-75 3450);
DISPLAY INVISIBLE (-75 3450);
FORCEADD TAP..1
R 2
(-75 3500);
FORCEPROP 3 LASTPIN (-25 3500) SIG_NAME M_BMC_DDR4_DQ<2>
J 0
(-15 3510);
DISPLAY 0.659574 (-15 3510);
PAINT MONO (-15 3510);
DISPLAY INVISIBLE (-15 3510);
FORCEPROP 1 LASTPIN (-25 3500) BN 2
J 2
(-13 3508);
DISPLAY 0.702128 (-13 3508);
PAINT VIOLET (-13 3508);
FORCEPROP 1 LAST PATH I68
J 2
(-73 3500);
DISPLAY 0.872340 (-73 3500);
PAINT GREEN (-73 3500);
DISPLAY INVISIBLE (-73 3500);
FORCEPROP 1 LAST HDL_TAP TRUE
J 2
(-400 3375);
DISPLAY 0.872340 (-400 3375);
DISPLAY INVISIBLE (-400 3375);
FORCEPROP 1 LAST BODY_TYPE PLUMBING
J 2
(-75 3550);
DISPLAY 0.872340 (-75 3550);
PAINT GREEN (-75 3550);
DISPLAY INVISIBLE (-75 3550);
FORCEPROP 2 LAST CDS_LIB standard
J 0
(-75 3500);
DISPLAY INVISIBLE (-75 3500);
FORCEADD TAP..1
R 2
(-75 3600);
FORCEPROP 3 LASTPIN (-25 3600) SIG_NAME M_BMC_DDR4_DQ<0>
J 0
(-15 3610);
DISPLAY 0.659574 (-15 3610);
PAINT MONO (-15 3610);
DISPLAY INVISIBLE (-15 3610);
FORCEPROP 1 LASTPIN (-25 3600) BN 0
J 2
(-13 3608);
DISPLAY 0.702128 (-13 3608);
PAINT VIOLET (-13 3608);
FORCEPROP 1 LAST PATH I69
J 2
(-73 3600);
DISPLAY 0.872340 (-73 3600);
PAINT GREEN (-73 3600);
DISPLAY INVISIBLE (-73 3600);
FORCEPROP 1 LAST HDL_TAP TRUE
J 2
(-400 3475);
DISPLAY 0.872340 (-400 3475);
DISPLAY INVISIBLE (-400 3475);
FORCEPROP 1 LAST BODY_TYPE PLUMBING
J 2
(-75 3650);
DISPLAY 0.872340 (-75 3650);
PAINT GREEN (-75 3650);
DISPLAY INVISIBLE (-75 3650);
FORCEPROP 2 LAST CDS_LIB standard
J 0
(-75 3600);
DISPLAY INVISIBLE (-75 3600);
FORCEADD TAP..1
R 2
(-75 3550);
FORCEPROP 3 LASTPIN (-25 3550) SIG_NAME M_BMC_DDR4_DQ<1>
J 0
(-15 3560);
DISPLAY 0.659574 (-15 3560);
PAINT MONO (-15 3560);
DISPLAY INVISIBLE (-15 3560);
FORCEPROP 1 LASTPIN (-25 3550) BN 1
J 2
(-13 3558);
DISPLAY 0.702128 (-13 3558);
PAINT VIOLET (-13 3558);
FORCEPROP 1 LAST PATH I70
J 2
(-73 3550);
DISPLAY 0.872340 (-73 3550);
PAINT GREEN (-73 3550);
DISPLAY INVISIBLE (-73 3550);
FORCEPROP 1 LAST HDL_TAP TRUE
J 2
(-400 3425);
DISPLAY 0.872340 (-400 3425);
DISPLAY INVISIBLE (-400 3425);
FORCEPROP 1 LAST BODY_TYPE PLUMBING
J 2
(-75 3600);
DISPLAY 0.872340 (-75 3600);
PAINT GREEN (-75 3600);
DISPLAY INVISIBLE (-75 3600);
FORCEPROP 2 LAST CDS_LIB standard
J 0
(-75 3550);
DISPLAY INVISIBLE (-75 3550);
FORCEADD OFFPAGE..4
R 2
(-2125 350);
FORCEPROP 2 LAST $XR1 11 
J 0
(-2466 350);
DISPLAY 0.638298 (-2466 350);
PAINT MONO (-2466 350);
FORCEPROP 2 LAST $XR0 10 
J 0
(-2376 350);
DISPLAY 0.638298 (-2376 350);
PAINT MONO (-2376 350);
FORCEPROP 2 LAST PATH I8
J 0
(-2325 400);
DISPLAY 1.021277 (-2325 400);
DISPLAY INVISIBLE (-2325 400);
FORCEPROP 1 LAST COMMENT_BODY TRUE
J 2
(-2100 250);
DISPLAY 0.872340 (-2100 250);
PAINT PEACH (-2100 250);
DISPLAY INVISIBLE (-2100 250);
FORCEPROP 1 LAST OFFPAGE TRUE
J 2
(-2450 225);
DISPLAY 0.872340 (-2450 225);
PAINT GREEN (-2450 225);
DISPLAY INVISIBLE (-2450 225);
FORCEPROP 2 LAST CDS_LIB standard
J 0
(-2125 350);
DISPLAY INVISIBLE (-2125 350);
FORCEADD Q_RES..1
(4125 1250);
FORCEPROP 1 LAST MATERIAL CHIP
J 2
(4500 1250);
DISPLAY 0.510638 (4500 1250);
PAINT SKYBLUE (4500 1250);
FORCEPROP 1 LAST VALUE 33.2
J 0
(4250 1250);
DISPLAY 0.510638 (4250 1250);
PAINT SKYBLUE (4250 1250);
FORCEPROP 1 LAST PACK_TYPE 0402LF
J 0
(4375 1100);
DISPLAY 0.510638 (4375 1100);
PAINT SKYBLUE (4375 1100);
DISPLAY INVISIBLE (4375 1100);
FORCEPROP 1 LAST WATTAGE 1/16W
J 2
(4100 1100);
DISPLAY 0.510638 (4100 1100);
PAINT SKYBLUE (4100 1100);
DISPLAY INVISIBLE (4100 1100);
FORCEPROP 1 LAST PATH I88
J 0
(4075 1400);
DISPLAY 0.978723 (4075 1400);
PAINT WHITE (4075 1400);
DISPLAY INVISIBLE (4075 1400);
FORCEPROP 2 LAST CDS_LIB pure_quanta
J 0
(4125 1250);
DISPLAY INVISIBLE (4125 1250);
FORCEPROP 1 LAST PART_NUMBER CS03322FB03
J 0
(4075 1350);
DISPLAY 0.510638 (4075 1350);
PAINT WHITE (4075 1350);
DISPLAY INVISIBLE (4075 1350);
FORCEPROP 1 LAST TOLERANCE 1%
J 0
(4250 1250);
DISPLAY 0.510638 (4250 1250);
PAINT SKYBLUE (4250 1250);
DISPLAY INVISIBLE (4250 1250);
FORCEPROP 1 LAST LOCATION R142
J 2
(3950 1250);
DISPLAY 0.702128 (3950 1250);
PAINT YELLOW (3950 1250);
FORCEPROP 0 LAST $SEC 1
J 0
(3875 1300);
DISPLAY 0.680851 (3875 1300);
PAINT MONO (3875 1300);
DISPLAY INVISIBLE (3875 1300);
FORCEPROP 0 LAST CDS_SEC 1
J 0
(3875 1300);
DISPLAY 1.021277 (3875 1300);
DISPLAY INVISIBLE (3875 1300);
FORCEPROP 1 LASTPIN (4025 1250) $PN 1
J 0
(4037 1262);
DISPLAY 0.808511 (4037 1262);
PAINT WHITE (4037 1262);
DISPLAY INVISIBLE (4037 1262);
FORCEPROP 1 LASTPIN (4225 1250) $PN 2
J 0
(4187 1262);
DISPLAY 0.808511 (4187 1262);
PAINT WHITE (4187 1262);
DISPLAY INVISIBLE (4187 1262);
FORCEADD Q_RES..1
(4125 1200);
FORCEPROP 1 LAST MATERIAL CHIP
J 2
(4500 1200);
DISPLAY 0.510638 (4500 1200);
PAINT SKYBLUE (4500 1200);
FORCEPROP 1 LAST VALUE 33.2
J 0
(4250 1200);
DISPLAY 0.510638 (4250 1200);
PAINT SKYBLUE (4250 1200);
FORCEPROP 1 LAST PACK_TYPE 0402LF
J 0
(4375 1050);
DISPLAY 0.510638 (4375 1050);
PAINT SKYBLUE (4375 1050);
DISPLAY INVISIBLE (4375 1050);
FORCEPROP 1 LAST WATTAGE 1/16W
J 2
(4100 1050);
DISPLAY 0.510638 (4100 1050);
PAINT SKYBLUE (4100 1050);
DISPLAY INVISIBLE (4100 1050);
FORCEPROP 1 LAST PATH I89
J 0
(4075 1350);
DISPLAY 0.978723 (4075 1350);
PAINT WHITE (4075 1350);
DISPLAY INVISIBLE (4075 1350);
FORCEPROP 2 LAST CDS_LIB pure_quanta
J 0
(4125 1200);
DISPLAY INVISIBLE (4125 1200);
FORCEPROP 1 LAST PART_NUMBER CS03322FB03
J 0
(4075 1300);
DISPLAY 0.510638 (4075 1300);
PAINT WHITE (4075 1300);
DISPLAY INVISIBLE (4075 1300);
FORCEPROP 1 LAST TOLERANCE 1%
J 0
(4250 1200);
DISPLAY 0.510638 (4250 1200);
PAINT SKYBLUE (4250 1200);
DISPLAY INVISIBLE (4250 1200);
FORCEPROP 1 LAST LOCATION R143
J 2
(3950 1200);
DISPLAY 0.702128 (3950 1200);
PAINT YELLOW (3950 1200);
FORCEPROP 1 LASTPIN (4025 1200) $PN 1
J 0
(4037 1212);
DISPLAY 0.808511 (4037 1212);
PAINT WHITE (4037 1212);
FORCEPROP 1 LASTPIN (4225 1200) $PN 2
J 0
(4187 1212);
DISPLAY 0.808511 (4187 1212);
PAINT WHITE (4187 1212);
FORCEPROP 0 LAST $SEC 1
J 0
(4225 1250);
DISPLAY 0.680851 (4225 1250);
PAINT MONO (4225 1250);
DISPLAY INVISIBLE (4225 1250);
FORCEPROP 0 LAST CDS_SEC 1
J 0
(4225 1250);
DISPLAY 0.680851 (4225 1250);
DISPLAY INVISIBLE (4225 1250);
FORCEADD OFFPAGE..2
R 2
(-2125 400);
FORCEPROP 2 LAST $XR1 10 
J 0
(-2469 400);
DISPLAY 0.638298 (-2469 400);
PAINT MONO (-2469 400);
FORCEPROP 2 LAST $XR0 11 
J 0
(-2379 400);
DISPLAY 0.638298 (-2379 400);
PAINT MONO (-2379 400);
FORCEPROP 2 LAST PATH I9
J 0
(-2300 450);
DISPLAY 1.021277 (-2300 450);
DISPLAY INVISIBLE (-2300 450);
FORCEPROP 1 LAST COMMENT_BODY TRUE
J 2
(-2080 305);
DISPLAY 0.872340 (-2080 305);
PAINT PEACH (-2080 305);
DISPLAY INVISIBLE (-2080 305);
FORCEPROP 1 LAST OFFPAGE TRUE
J 2
(-2450 275);
DISPLAY 0.872340 (-2450 275);
PAINT GREEN (-2450 275);
DISPLAY INVISIBLE (-2450 275);
FORCEPROP 2 LAST CDS_LIB standard
J 0
(-2125 400);
DISPLAY INVISIBLE (-2125 400);
FORCEADD Q_RES..1
(4125 1800);
FORCEPROP 1 LAST MATERIAL CHIP
J 2
(4500 1800);
DISPLAY 0.510638 (4500 1800);
PAINT SKYBLUE (4500 1800);
FORCEPROP 1 LAST VALUE 33.2
J 0
(4250 1800);
DISPLAY 0.510638 (4250 1800);
PAINT SKYBLUE (4250 1800);
FORCEPROP 1 LAST PACK_TYPE 0402LF
J 0
(4375 1650);
DISPLAY 0.510638 (4375 1650);
PAINT SKYBLUE (4375 1650);
DISPLAY INVISIBLE (4375 1650);
FORCEPROP 1 LAST WATTAGE 1/16W
J 2
(4100 1650);
DISPLAY 0.510638 (4100 1650);
PAINT SKYBLUE (4100 1650);
DISPLAY INVISIBLE (4100 1650);
FORCEPROP 1 LAST PATH I97
J 0
(4075 1950);
DISPLAY 0.978723 (4075 1950);
PAINT WHITE (4075 1950);
DISPLAY INVISIBLE (4075 1950);
FORCEPROP 2 LAST CDS_LIB pure_quanta
J 0
(4125 1800);
DISPLAY INVISIBLE (4125 1800);
FORCEPROP 1 LAST PART_NUMBER CS03322FB03
J 0
(4075 1900);
DISPLAY 0.510638 (4075 1900);
PAINT WHITE (4075 1900);
DISPLAY INVISIBLE (4075 1900);
FORCEPROP 1 LAST TOLERANCE 1%
J 0
(4250 1800);
DISPLAY 0.510638 (4250 1800);
PAINT SKYBLUE (4250 1800);
DISPLAY INVISIBLE (4250 1800);
FORCEPROP 1 LAST LOCATION R133
J 2
(3950 1800);
DISPLAY 0.702128 (3950 1800);
PAINT YELLOW (3950 1800);
FORCEPROP 1 LASTPIN (4025 1800) $PN 1
J 0
(4037 1812);
DISPLAY 0.808511 (4037 1812);
PAINT WHITE (4037 1812);
FORCEPROP 1 LASTPIN (4225 1800) $PN 2
J 0
(4187 1812);
DISPLAY 0.808511 (4187 1812);
PAINT WHITE (4187 1812);
FORCEPROP 0 LAST $SEC 1
J 0
(4225 1850);
DISPLAY 0.680851 (4225 1850);
PAINT MONO (4225 1850);
DISPLAY INVISIBLE (4225 1850);
FORCEPROP 0 LAST CDS_SEC 1
J 0
(4225 1850);
DISPLAY 0.680851 (4225 1850);
DISPLAY INVISIBLE (4225 1850);
FORCEADD Q_RES..1
(4125 1850);
FORCEPROP 1 LAST VALUE 33.2
J 0
(4250 1850);
DISPLAY 0.510638 (4250 1850);
PAINT SKYBLUE (4250 1850);
FORCEPROP 1 LAST MATERIAL CHIP
J 2
(4500 1850);
DISPLAY 0.510638 (4500 1850);
PAINT SKYBLUE (4500 1850);
FORCEPROP 1 LAST PACK_TYPE 0402LF
J 0
(4375 1700);
DISPLAY 0.510638 (4375 1700);
PAINT SKYBLUE (4375 1700);
DISPLAY INVISIBLE (4375 1700);
FORCEPROP 1 LAST WATTAGE 1/16W
J 2
(4100 1700);
DISPLAY 0.510638 (4100 1700);
PAINT SKYBLUE (4100 1700);
DISPLAY INVISIBLE (4100 1700);
FORCEPROP 1 LAST PATH I98
J 0
(4075 2000);
DISPLAY 0.978723 (4075 2000);
PAINT WHITE (4075 2000);
DISPLAY INVISIBLE (4075 2000);
FORCEPROP 2 LAST CDS_LIB pure_quanta
J 0
(4125 1850);
DISPLAY INVISIBLE (4125 1850);
FORCEPROP 1 LAST PART_NUMBER CS03322FB03
J 0
(4075 1950);
DISPLAY 0.510638 (4075 1950);
PAINT WHITE (4075 1950);
DISPLAY INVISIBLE (4075 1950);
FORCEPROP 1 LAST TOLERANCE 1%
J 0
(4250 1850);
DISPLAY 0.510638 (4250 1850);
PAINT SKYBLUE (4250 1850);
DISPLAY INVISIBLE (4250 1850);
FORCEPROP 1 LAST LOCATION R132
J 2
(3950 1850);
DISPLAY 0.702128 (3950 1850);
PAINT YELLOW (3950 1850);
FORCEPROP 0 LAST $SEC 1
J 0
(3875 1900);
DISPLAY 0.680851 (3875 1900);
PAINT MONO (3875 1900);
DISPLAY INVISIBLE (3875 1900);
FORCEPROP 0 LAST CDS_SEC 1
J 0
(3875 1900);
DISPLAY 1.021277 (3875 1900);
DISPLAY INVISIBLE (3875 1900);
FORCEPROP 1 LASTPIN (4025 1850) $PN 1
J 0
(4037 1862);
DISPLAY 0.808511 (4037 1862);
PAINT WHITE (4037 1862);
DISPLAY INVISIBLE (4037 1862);
FORCEPROP 1 LASTPIN (4225 1850) $PN 2
J 0
(4187 1862);
DISPLAY 0.808511 (4187 1862);
PAINT WHITE (4187 1862);
DISPLAY INVISIBLE (4187 1862);
FORCEADD QUANTA_TITLE_BLOCK_C..1
(6400 -1500);
FORCEPROP 0 LAST CDS_CON_LAST_MODIFIED Fri Aug 25 17:25:36 2023
J 0
(4515 -1485);
DISPLAY INVISIBLE (4515 -1485);
FORCEPROP 2 LAST Q_DEPT 
J 1
(2637 -1451);
DISPLAY 1.957447 (2637 -1451);
PAINT GREEN (2637 -1451);
FORCEPROP 1 LAST CUSTOM_TXT_CDS <CON_LAST_MODIFIED>
J 0
(4515 -1485);
DISPLAY 0.978723 (4515 -1485);
FORCEPROP 2 LAST CUSTOM_TXT_CDS <XR_PAGE_TITLE>
J 0
(-1490 3750);
DISPLAY 0.638298 (-1490 3750);
PAINT PINK (-1490 3750);
DISPLAY INVISIBLE (-1490 3750);
FORCEPROP 1 LAST CUSTOM_TXT_CDS <NAME_2>
J 0
(3225 -1450);
FORCEPROP 1 LAST CUSTOM_TXT_CDS <NAME_1>
J 0
(3225 -1325);
FORCEPROP 1 LAST CUSTOM_TXT_CDS <Q_NUMBER>
J 0
(4997 -1397);
DISPLAY 1.212766 (4997 -1397);
FORCEPROP 1 LAST CUSTOM_TXT_CDS <Q_PROJ>
J 0
(4018 -1398);
DISPLAY 1.212766 (4018 -1398);
FORCEPROP 1 LAST CUSTOM_TXT_CDS <Q_REV>
J 0
(6216 -1397);
DISPLAY 1.212766 (6216 -1397);
FORCEPROP 1 LAST CUSTOM_TXT_CDS <CON_PAGE_NUM> OF <CON_TOTAL_PAGES>
J 0
(5954 -1482);
DISPLAY 0.978723 (5954 -1482);
FORCEPROP 1 LAST Q_TITLE BMC 1
J 0
(-2966 -1474);
DISPLAY 2.446809 (-2966 -1474);
PAINT GREEN (-2966 -1474);
FORCEPROP 1 LAST COMMENT_BODY TRUE
J 0
(6412 -1513);
DISPLAY 0.978723 (6412 -1513);
PAINT PEACH (6412 -1513);
DISPLAY INVISIBLE (6412 -1513);
FORCEPROP 2 LAST PAGE_BORDER TRUE
J 0
(-1490 3750);
DISPLAY 0.638298 (-1490 3750);
PAINT PINK (-1490 3750);
DISPLAY INVISIBLE (-1490 3750);
FORCEPROP 2 LAST CDS_LIB pure_quanta
J 0
(6400 -1500);
DISPLAY INVISIBLE (6400 -1500);
FORCEPROP 1 LAST CDS_LMAN_SYM_OUTLINE -9475,6775,100,-125
J 0
(6400 -1500);
DISPLAY 0.468085 (6400 -1500);
PAINT GREEN (6400 -1500);
DISPLAY INVISIBLE (6400 -1500);
FORCEPROP 2 LAST CDS_XR_PAGE_TITLE CR-12 : @SCM_LIB.SCM(SCH_1):PAGE12
J 0
(-1490 3750);
DISPLAY 0.638298 (-1490 3750);
PAINT PINK (-1490 3750);
DISPLAY INVISIBLE (-1490 3750);
FORCEADD DNS..2
(-1475 -450);
PAINT RED (-1475 -450);
FORCEPROP 1 LAST COMMENT_BODY TRUE
R 1
J 0
(-1400 -675);
DISPLAY 0.872340 (-1400 -675);
PAINT PEACH (-1400 -675);
DISPLAY INVISIBLE (-1400 -675);
FORCEPROP 2 LAST CDS_LIB mstr_misc
J 0
(-1475 -450);
DISPLAY INVISIBLE (-1475 -450);
FORCEADD DNS..2
(-1475 -300);
PAINT RED (-1475 -300);
FORCEPROP 2 LAST CDS_LIB mstr_misc
J 0
(-1475 -300);
DISPLAY INVISIBLE (-1475 -300);
FORCEPROP 1 LAST COMMENT_BODY TRUE
R 1
J 0
(-1400 -525);
DISPLAY 0.872340 (-1400 -525);
PAINT PEACH (-1400 -525);
DISPLAY INVISIBLE (-1400 -525);
FORCEADD DNS..1
(-2200 2600);
PAINT RED (-2200 2600);
FORCEPROP 1 LAST COMMENT_BODY TRUE
R 1
J 0
(-2125 2375);
DISPLAY 0.872340 (-2125 2375);
PAINT PEACH (-2125 2375);
DISPLAY INVISIBLE (-2125 2375);
FORCEPROP 2 LAST CDS_LIB mstr_misc
J 0
(-2200 2600);
DISPLAY INVISIBLE (-2200 2600);
FORCEADD DNS..2
(2525 -325);
PAINT RED (2525 -325);
FORCEPROP 1 LAST COMMENT_BODY TRUE
R 1
J 0
(2600 -550);
DISPLAY 0.872340 (2600 -550);
PAINT PEACH (2600 -550);
DISPLAY INVISIBLE (2600 -550);
FORCEPROP 2 LAST CDS_LIB mstr_misc
J 0
(2525 -325);
DISPLAY INVISIBLE (2525 -325);
FORCEADD DNS..2
(4625 -950);
PAINT RED (4625 -950);
FORCEPROP 2 LAST CDS_LIB mstr_misc
J 0
(4625 -950);
DISPLAY INVISIBLE (4625 -950);
FORCEPROP 1 LAST COMMENT_BODY TRUE
R 1
J 0
(4700 -1175);
DISPLAY 0.872340 (4700 -1175);
PAINT PEACH (4700 -1175);
DISPLAY INVISIBLE (4700 -1175);
WIRE 17 -1 (4225 2475)(4225 2425);
WIRE 17 -1 (4225 2525)(4225 2475);
WIRE 17 -1 (4225 2575)(4225 2525);
WIRE 17 -1 (4225 2625)(4225 2575);
WIRE 17 -1 (4225 2675)(4225 2625);
WIRE 17 -1 (4225 2725)(4225 2675);
WIRE 17 -1 (4225 2775)(4225 2725);
WIRE 17 -1 (4225 2825)(4225 2775);
WIRE 17 -1 (4225 2875)(4225 2825);
WIRE 17 -1 (4225 2925)(4225 2875);
WIRE 17 -1 (4225 2975)(4225 2925);
WIRE 17 -1 (4225 3025)(4225 2975);
WIRE 17 -1 (4225 3075)(4225 3025);
WIRE 17 -1 (4225 3075)(4225 3125);
WIRE 17 -1 (4225 3125)(5000 3125);
FORCEPROP 2 LAST SIG_NAME M_BMC_DDR4_MA<13:0>
J 0
(4265 3135);
DISPLAY 0.808511 (4265 3135);
WIRE 17 -1 (-125 3425)(-125 3375);
WIRE 17 -1 (-125 3475)(-125 3425);
WIRE 17 -1 (-125 3375)(-125 3325);
WIRE 17 -1 (-125 3325)(-125 3275);
WIRE 17 -1 (-125 3525)(-125 3475);
WIRE 17 -1 (-125 3575)(-125 3525);
WIRE 17 -1 (-125 3275)(-125 3225);
WIRE 17 -1 (-125 3225)(-125 3175);
WIRE 17 -1 (-125 3625)(-125 3575);
WIRE 17 -1 (-125 3650)(-125 3625);
WIRE 17 -1 (-125 3175)(-125 3125);
WIRE 17 -1 (-125 3125)(-125 3075);
WIRE 17 -1 (-950 3650)(-125 3650);
FORCEPROP 2 LAST SIG_NAME M_BMC_DDR4_DQ<15:0>
J 0
(-910 3660);
DISPLAY 0.808511 (-910 3660);
WIRE 17 -1 (-125 2925)(-125 2875);
WIRE 17 -1 (-125 2975)(-125 2925);
WIRE 17 -1 (-125 3025)(-125 2975);
WIRE 17 -1 (-125 3075)(-125 3025);
WIRE 16 -1 (-2200 2950)(-2200 2875);
WIRE 16 -1 (-2775 3375)(-2775 3300);
WIRE 16 -1 (4200 -950)(4200 -850);
WIRE 16 -1 (4500 -950)(4200 -950);
WIRE 16 -1 (-1875 -325)(-1875 -225);
WIRE 16 -1 (-1575 -325)(-1875 -325);
WIRE 16 -1 (-1875 -375)(-1875 -325);
WIRE 16 -1 (-1700 2350)(-1700 2250);
WIRE 16 -1 (-1700 2350)(-1550 2350);
WIRE 16 -1 (-1875 2350)(-1700 2350);
WIRE 16 -1 (-300 2200)(-750 2200);
WIRE 16 -1 (2250 -475)(2250 -400);
WIRE 16 -1 (-1275 -725)(-1275 -775);
WIRE 16 -1 (-1550 3650)(-1550 3800);
WIRE 16 -1 (-1500 4725)(-1500 4800);
WIRE 16 -1 (2875 1650)(4025 1650);
FORCEPROP 2 LAST SIG_NAME SMB_BMC_MM3_R_SCL
J 2
(3750 1660);
DISPLAY 0.808511 (3750 1660);
WIRE 16 -1 (2875 1600)(4025 1600);
FORCEPROP 2 LAST SIG_NAME SMB_BMC_MM3_R_SDA
J 2
(3750 1610);
DISPLAY 0.808511 (3750 1610);
WIRE 16 -1 (4025 1550)(2875 1550);
FORCEPROP 2 LAST SIG_NAME SMB_BMC_MM4_R_SCL
J 0
(3100 1560);
DISPLAY 0.808511 (3100 1560);
WIRE 16 -1 (4025 1500)(2875 1500);
FORCEPROP 2 LAST SIG_NAME SMB_BMC_MM4_R_SDA
J 0
(3100 1510);
DISPLAY 0.808511 (3100 1510);
WIRE 16 -1 (5250 1350)(2875 1350);
FORCEPROP 2 LAST SIG_NAME SMB_BMC_MM5_R_SCL
J 2
(5225 1350);
DISPLAY 0.808511 (5225 1350);
WIRE 16 -1 (5250 1050)(4225 1050);
FORCEPROP 2 LAST SIG_NAME SMB_BMC_MM8_SCL
J 2
(5225 1060);
DISPLAY 0.808511 (5225 1060);
WIRE 16 -1 (5250 1000)(4225 1000);
FORCEPROP 2 LAST SIG_NAME SMB_BMC_MM8_SDA
J 2
(5225 1010);
DISPLAY 0.808511 (5225 1010);
WIRE 16 -1 (5250 900)(2875 900);
FORCEPROP 2 LAST SIG_NAME SMB_BMC_MM9_R_SCL
J 2
(5225 910);
DISPLAY 0.808511 (5225 910);
WIRE 16 -1 (5250 850)(2875 850);
FORCEPROP 2 LAST SIG_NAME SMB_BMC_MM9_R_SDA
J 2
(5225 860);
DISPLAY 0.808511 (5225 860);
WIRE 16 -1 (5250 800)(2875 800);
FORCEPROP 2 LAST SIG_NAME SMB_BMC_MM10_R_SCL
J 2
(5225 810);
DISPLAY 0.808511 (5225 810);
WIRE 16 -1 (5250 750)(2875 750);
FORCEPROP 2 LAST SIG_NAME SMB_BMC_MM10_R_SDA
J 2
(5225 760);
DISPLAY 0.808511 (5225 760);
WIRE 16 -1 (4025 1050)(2875 1050);
FORCEPROP 2 LAST SIG_NAME SMB_BMC_MM8_R_SCL
J 0
(3100 1060);
DISPLAY 0.808511 (3100 1060);
WIRE 16 -1 (4025 1000)(2875 1000);
FORCEPROP 2 LAST SIG_NAME SMB_BMC_MM8_R_SDA
J 0
(3100 1010);
DISPLAY 0.808511 (3100 1010);
WIRE 16 -1 (5250 1100)(2875 1100);
FORCEPROP 2 LAST SIG_NAME SMB_BMC_MM7_R_SDA
J 2
(5225 1100);
DISPLAY 0.808511 (5225 1100);
WIRE 16 -1 (5250 1200)(4225 1200);
FORCEPROP 2 LAST SIG_NAME SMB_BMC_MM6_SDA
J 2
(5225 1210);
DISPLAY 0.808511 (5225 1210);
WIRE 16 -1 (5250 1250)(4225 1250);
FORCEPROP 2 LAST SIG_NAME SMB_BMC_MM6_SCL
J 2
(5225 1260);
DISPLAY 0.808511 (5225 1260);
WIRE 16 -1 (5250 1500)(4225 1500);
FORCEPROP 2 LAST SIG_NAME SMB_BMC_MM4_SDA
J 2
(5225 1510);
DISPLAY 0.808511 (5225 1510);
WIRE 16 -1 (5250 1300)(2875 1300);
FORCEPROP 2 LAST SIG_NAME SMB_BMC_MM5_R_SDA
J 2
(5225 1300);
DISPLAY 0.808511 (5225 1300);
WIRE 16 -1 (4025 1250)(2875 1250);
FORCEPROP 2 LAST SIG_NAME SMB_BMC_MM6_R_SCL
J 0
(3100 1260);
DISPLAY 0.808511 (3100 1260);
WIRE 16 -1 (4025 1200)(2875 1200);
FORCEPROP 2 LAST SIG_NAME SMB_BMC_MM6_R_SDA
J 0
(3100 1210);
DISPLAY 0.808511 (3100 1210);
WIRE 16 -1 (5250 1150)(2875 1150);
FORCEPROP 2 LAST SIG_NAME SMB_BMC_MM7_R_SCL
J 2
(5225 1150);
DISPLAY 0.808511 (5225 1150);
WIRE 16 3135 (4075 1525)(4175 1525);
WIRE 16 3135 (4075 1575)(4075 1525);
WIRE 16 3135 (4175 1525)(4175 1575);
WIRE 16 3135 (4175 1575)(4075 1575);
WIRE 16 -1 (5250 1550)(4225 1550);
FORCEPROP 2 LAST SIG_NAME SMB_BMC_MM4_SCL
J 2
(5225 1560);
DISPLAY 0.808511 (5225 1560);
WIRE 16 -1 (4225 1600)(5250 1600);
FORCEPROP 2 LAST SIG_NAME SMB_BMC_MM3_SDA
J 2
(5225 1610);
DISPLAY 0.808511 (5225 1610);
WIRE 16 -1 (4225 1650)(5250 1650);
FORCEPROP 2 LAST SIG_NAME SMB_BMC_MM3_SCL
J 2
(5225 1660);
DISPLAY 0.808511 (5225 1660);
WIRE 16 -1 (4225 1700)(5250 1700);
FORCEPROP 2 LAST SIG_NAME SMB_BMC_MM2_SDA
J 2
(5225 1710);
DISPLAY 0.808511 (5225 1710);
WIRE 16 -1 (3100 -400)(2650 -400);
WIRE 16 -1 (2875 100)(3100 100);
WIRE 16 -1 (3100 100)(4275 100);
FORCEPROP 2 LAST SIG_NAME SMB_BMC_MM14_R_SDA
J 0
(3190 110);
DISPLAY 0.808511 (3190 110);
WIRE 16 -1 (3100 100)(3100 -400);
WIRE 16 -1 (4475 150)(5825 150);
FORCEPROP 2 LAST SIG_NAME SMB_BMC_MM14_SCL
J 2
(5490 160);
DISPLAY 0.808511 (5490 160);
WIRE 16 -1 (4475 200)(5825 200);
FORCEPROP 2 LAST SIG_NAME SMB_BMC_MM13_SDA
J 2
(5490 210);
DISPLAY 0.808511 (5490 210);
WIRE 16 -1 (4475 250)(5825 250);
FORCEPROP 2 LAST SIG_NAME SMB_BMC_MM13_SCL
J 2
(5490 260);
DISPLAY 0.808511 (5490 260);
WIRE 16 -1 (5250 500)(4225 500);
FORCEPROP 2 LAST SIG_NAME SMB_BMC_MM12_SDA
J 2
(5225 510);
DISPLAY 0.808511 (5225 510);
WIRE 16 -1 (5250 550)(4225 550);
FORCEPROP 2 LAST SIG_NAME SMB_BMC_MM12_SCL
J 2
(5225 560);
DISPLAY 0.808511 (5225 560);
WIRE 16 -1 (2875 600)(5250 600);
FORCEPROP 2 LAST SIG_NAME RST_PFR_OVR_RTC_R
J 0
(4590 610);
DISPLAY 0.808511 (4590 610);
WIRE 16 -1 (2875 650)(5250 650);
FORCEPROP 2 LAST SIG_NAME FM_PFR_DSW_PWROK_N
J 0
(4540 660);
DISPLAY 0.808511 (4540 660);
WIRE 16 -1 (4475 100)(5825 100);
FORCEPROP 2 LAST SIG_NAME SMB_BMC_MM14_SDA
J 2
(5490 110);
DISPLAY 0.808511 (5490 110);
WIRE 16 -1 (2875 1700)(4025 1700);
FORCEPROP 2 LAST SIG_NAME SMB_BMC_MM2_R_SDA
J 2
(3750 1710);
DISPLAY 0.808511 (3750 1710);
WIRE 16 -1 (2875 1750)(4025 1750);
FORCEPROP 2 LAST SIG_NAME SMB_BMC_MM2_R_SCL
J 2
(3750 1760);
DISPLAY 0.808511 (3750 1760);
WIRE 16 -1 (775 2300)(150 2300);
WIRE 16 -1 (150 2350)(150 2300);
WIRE 16 -1 (150 2350)(775 2350);
WIRE 16 -1 (150 2350)(-1225 2350);
WIRE 16 -1 (-1225 2350)(-1225 2875);
WIRE 16 -1 (-1550 2725)(-1550 2875);
WIRE 16 -1 (-1225 2875)(-1550 2875);
WIRE 16 -1 (-2200 2875)(-2200 2725);
WIRE 16 -1 (-1875 2875)(-1875 2725);
WIRE 16 -1 (-1875 2875)(-1550 2875);
WIRE 16 -1 (-1875 2875)(-2200 2875);
WIRE 16 -1 (-750 1950)(775 1950);
FORCEPROP 2 LAST SIG_NAME RST_ESPI_LPC_BMC_N
J 0
(-635 1960);
DISPLAY 0.808511 (-635 1960);
WIRE 16 -1 (775 1750)(-2075 1750);
FORCEPROP 2 LAST SIG_NAME BMC_EMMC_CLK
J 0
(-1985 1760);
DISPLAY 0.808511 (-1985 1760);
WIRE 16 -1 (-750 2000)(775 2000);
FORCEPROP 2 LAST SIG_NAME IRQ_ESPI_LPC_SERIRQ_ALERT0_N
J 0
(-635 2010);
DISPLAY 0.808511 (-635 2010);
WIRE 16 -1 (-750 2050)(775 2050);
FORCEPROP 2 LAST SIG_NAME ESPI_HOST_LPC_BMC_LFRAME_N_R
J 0
(-635 2060);
DISPLAY 0.851064 (-635 2060);
WIRE 16 -1 (775 1550)(-2075 1550);
FORCEPROP 2 LAST SIG_NAME BMC_EMMC_DT2
J 0
(-1985 1560);
DISPLAY 0.808511 (-1985 1560);
WIRE 16 -1 (775 1500)(-2075 1500);
FORCEPROP 2 LAST SIG_NAME BMC_EMMC_DT3
J 0
(-1985 1510);
DISPLAY 0.808511 (-1985 1510);
WIRE 16 -1 (-2075 1450)(775 1450);
FORCEPROP 2 LAST SIG_NAME BMC_EMMC_CD_N
J 0
(-1985 1460);
DISPLAY 0.808511 (-1985 1460);
WIRE 16 -1 (-2075 1400)(775 1400);
FORCEPROP 2 LAST SIG_NAME BMC_EMMC_WP_N
J 0
(-1985 1410);
DISPLAY 0.808511 (-1985 1410);
WIRE 16 -1 (-2075 1100)(-950 1100);
FORCEPROP 2 LAST SIG_NAME UART_6_BMC_TXD
J 2
(-1500 1110);
DISPLAY 0.808511 (-1500 1110);
WIRE 16 -1 (-1550 3800)(-675 3800);
WIRE 16 -1 (-750 2100)(775 2100);
FORCEPROP 2 LAST SIG_NAME ESPI_HOST_LPC_BMC_CLK_R
J 0
(-635 2110);
DISPLAY 0.851064 (-635 2110);
WIRE 16 -1 (775 1700)(-2075 1700);
FORCEPROP 2 LAST SIG_NAME BMC_EMMC_CMD
J 0
(-1985 1710);
DISPLAY 0.808511 (-1985 1710);
WIRE 16 -1 (775 1650)(-2075 1650);
FORCEPROP 2 LAST SIG_NAME BMC_EMMC_DT0
J 0
(-1985 1660);
DISPLAY 0.808511 (-1985 1660);
WIRE 16 -1 (775 1600)(-2075 1600);
FORCEPROP 2 LAST SIG_NAME BMC_EMMC_DT1
J 0
(-1985 1610);
DISPLAY 0.808511 (-1985 1610);
WIRE 16 -1 (-750 1100)(775 1100);
FORCEPROP 2 LAST SIG_NAME UART_6_BMC_R_TXD
J 2
(240 1110);
DISPLAY 0.808511 (240 1110);
WIRE 16 -1 (775 1000)(-2075 1000);
FORCEPROP 2 LAST SIG_NAME BMC_EMMC_DT4
J 0
(-2035 1010);
DISPLAY 0.808511 (-2035 1010);
WIRE 16 -1 (775 950)(-2075 950);
FORCEPROP 2 LAST SIG_NAME BMC_EMMC_DT5
J 0
(-2035 960);
DISPLAY 0.808511 (-2035 960);
WIRE 16 -1 (775 900)(-2075 900);
FORCEPROP 2 LAST SIG_NAME BMC_EMMC_DT6
J 0
(-2035 910);
DISPLAY 0.808511 (-2035 910);
WIRE 16 -1 (775 850)(-2075 850);
FORCEPROP 2 LAST SIG_NAME BMC_EMMC_DT7
J 0
(-2035 860);
DISPLAY 0.808511 (-2035 860);
WIRE 16 -1 (775 800)(-2075 800);
FORCEPROP 2 LAST SIG_NAME SMB_BMC_ALERT15_N
J 0
(-2035 810);
DISPLAY 0.808511 (-2035 810);
WIRE 16 -1 (-950 750)(-2075 750);
FORCEPROP 2 LAST SIG_NAME FM_BMC_DBP_PRESENT_N
J 0
(-2035 760);
DISPLAY 0.808511 (-2035 760);
WIRE 16 -1 (-750 450)(-2075 450);
FORCEPROP 2 LAST SIG_NAME SGPIO_LD_1
J 0
(-2050 460);
DISPLAY 0.808511 (-2050 460);
WIRE 16 -1 (-750 350)(-2075 350);
FORCEPROP 2 LAST SIG_NAME SGPIO_DI_1
J 0
(-2050 360);
DISPLAY 0.808511 (-2050 360);
WIRE 16 -1 (-750 300)(-2075 300);
FORCEPROP 2 LAST SIG_NAME SMB_BMC_MM15_SCL
J 0
(-2050 310);
DISPLAY 0.808511 (-2050 310);
WIRE 16 -1 (-750 250)(-2075 250);
FORCEPROP 2 LAST SIG_NAME SMB_BMC_MM15_SDA
J 0
(-2050 260);
DISPLAY 0.808511 (-2050 260);
WIRE 16 -1 (-1300 25)(-1125 25);
WIRE 16 -1 (-1125 25)(-1125 150);
WIRE 16 -1 (-1125 150)(-750 150);
WIRE 16 -1 (-2075 150)(-1125 150);
FORCEPROP 2 LAST SIG_NAME SMB_BMC_MM16_SDA
J 0
(-2050 160);
DISPLAY 0.808511 (-2050 160);
WIRE 16 3135 (-2125 -875)(-2125 -50);
WIRE 16 3135 (-2125 -875)(200 -875);
WIRE 16 3135 (200 -50)(-2125 -50);
WIRE 16 3135 (200 -50)(200 -875);
WIRE 16 -1 (-1875 -425)(-1575 -425);
WIRE 16 -1 (-1575 -375)(-1875 -375);
WIRE 16 -1 (-1875 -375)(-1875 -425);
WIRE 16 -1 (-1275 -525)(-1275 -425);
WIRE 16 -1 (-1275 -425)(-1375 -425);
WIRE 16 -1 (-250 -425)(-1275 -425);
FORCEPROP 2 LAST SIG_NAME RST_BMC_LPC_ESPI_N
J 0
(-1225 -415);
DISPLAY 0.808511 (-1225 -415);
WIRE 16 -1 (3625 -500)(4675 -500);
FORCEPROP 2 LAST SIG_NAME SMB_BMC_MM7_R_SDA
J 2
(4290 -490);
DISPLAY 0.808511 (4290 -490);
WIRE 16 -1 (5825 -450)(4875 -450);
FORCEPROP 2 LAST SIG_NAME SMB_BMC_MM7_SCL
J 2
(5790 -440);
DISPLAY 0.808511 (5790 -440);
WIRE 16 -1 (5825 -400)(4875 -400);
FORCEPROP 2 LAST SIG_NAME SMB_BMC_MM5_SDA
J 2
(5790 -390);
DISPLAY 0.808511 (5790 -390);
WIRE 16 -1 (4800 2100)(3925 2100);
FORCEPROP 2 LAST SIG_NAME ESPI_LPC_LAD0_IO0
J 0
(4140 2110);
DISPLAY 0.808511 (4140 2110);
WIRE 16 -1 (4800 2050)(3925 2050);
FORCEPROP 2 LAST SIG_NAME ESPI_LPC_LAD1_IO1
J 0
(4140 2060);
DISPLAY 0.808511 (4140 2060);
WIRE 16 -1 (4800 2000)(3925 2000);
FORCEPROP 2 LAST SIG_NAME ESPI_LPC_LAD2_IO2
J 0
(4140 2010);
DISPLAY 0.808511 (4140 2010);
WIRE 16 -1 (4800 1950)(3925 1950);
FORCEPROP 2 LAST SIG_NAME ESPI_LPC_LAD3_IO3
J 0
(4140 1960);
DISPLAY 0.808511 (4140 1960);
WIRE 16 -1 (5250 1850)(4225 1850);
FORCEPROP 2 LAST SIG_NAME SMB_BMC_MM1_SCL
J 2
(5225 1860);
DISPLAY 0.808511 (5225 1860);
WIRE 16 -1 (4025 1800)(2875 1800);
FORCEPROP 2 LAST SIG_NAME SMB_BMC_MM1_R_SDA
J 0
(3100 1810);
DISPLAY 0.808511 (3100 1810);
WIRE 16 -1 (4025 1850)(2875 1850);
FORCEPROP 2 LAST SIG_NAME SMB_BMC_MM1_R_SCL
J 0
(3100 1860);
DISPLAY 0.808511 (3100 1860);
WIRE 16 -1 (4225 1750)(5250 1750);
FORCEPROP 2 LAST SIG_NAME SMB_BMC_MM2_SCL
J 2
(5225 1760);
DISPLAY 0.808511 (5225 1760);
WIRE 16 -1 (5250 1800)(4225 1800);
FORCEPROP 2 LAST SIG_NAME SMB_BMC_MM1_SDA
J 2
(5225 1810);
DISPLAY 0.808511 (5225 1810);
WIRE 16 -1 (5825 -100)(2875 -100);
FORCEPROP 2 LAST SIG_NAME FM_TPM_PRSNT_1_N
J 0
(4815 -90);
DISPLAY 0.851064 (4815 -90);
WIRE 16 -1 (4025 500)(2875 500);
FORCEPROP 2 LAST SIG_NAME SMB_BMC_MM12_R_SDA
J 0
(3100 510);
DISPLAY 0.808511 (3100 510);
WIRE 16 -1 (3075 -350)(2650 -350);
WIRE 16 -1 (2875 150)(3075 150);
WIRE 16 -1 (3075 150)(4275 150);
FORCEPROP 0 LAST SIG_NAME SMB_BMC_MM14_R_SCL
J 0
(3190 160);
DISPLAY 0.808511 (3190 160);
WIRE 16 -1 (3075 150)(3075 -350);
WIRE 16 -1 (3050 -300)(2650 -300);
WIRE 16 -1 (2875 200)(3050 200);
WIRE 16 -1 (3050 200)(4275 200);
FORCEPROP 2 LAST SIG_NAME SMB_BMC_MM13_R_SDA
J 0
(3190 210);
DISPLAY 0.808511 (3190 210);
WIRE 16 -1 (3050 200)(3050 -300);
WIRE 16 -1 (2875 250)(3025 250);
WIRE 16 -1 (3025 250)(4275 250);
FORCEPROP 2 LAST SIG_NAME SMB_BMC_MM13_R_SCL
J 0
(3190 260);
DISPLAY 0.808511 (3190 260);
WIRE 16 -1 (3025 -250)(3025 250);
WIRE 16 -1 (2650 -250)(3025 -250);
WIRE 16 -1 (2875 2850)(4125 2850);
WIRE 16 -1 (2875 2950)(4125 2950);
WIRE 16 -1 (2875 3000)(4125 3000);
WIRE 16 -1 (2875 3050)(4125 3050);
WIRE 16 -1 (3650 3400)(2875 3400);
FORCEPROP 2 LAST SIG_NAME M_BMC_DDR4_MCS_N
J 0
(2965 3410);
DISPLAY 0.808511 (2965 3410);
WIRE 16 -1 (3650 3450)(2875 3450);
FORCEPROP 2 LAST SIG_NAME M_BMC_DDR4_MODT
J 0
(2965 3460);
DISPLAY 0.808511 (2965 3460);
WIRE 16 -1 (5825 -50)(2875 -50);
FORCEPROP 2 LAST SIG_NAME FM_THERMTRIP_DLY_LVC1_R_N
J 2
(5765 -40);
DISPLAY 0.808511 (5765 -40);
WIRE 16 -1 (-750 1050)(775 1050);
FORCEPROP 2 LAST SIG_NAME UART_6_BMC_R_RXD
J 2
(240 1060);
DISPLAY 0.808511 (240 1060);
WIRE 16 -1 (-1250 4800)(-1500 4800);
WIRE 16 -1 (2250 -250)(2450 -250);
WIRE 16 -1 (2250 -300)(2250 -250);
WIRE 16 -1 (2450 -300)(2250 -300);
WIRE 16 -1 (2250 -350)(2250 -300);
WIRE 16 -1 (2450 -350)(2250 -350);
WIRE 16 -1 (2250 -400)(2250 -350);
WIRE 16 -1 (2450 -400)(2250 -400);
WIRE 16 -1 (-2775 3225)(-2650 3225);
WIRE 16 -1 (-2775 3300)(-2775 3225);
WIRE 16 -1 (-2650 3300)(-2775 3300);
WIRE 16 -1 (-2200 2525)(-2200 2350);
WIRE 16 -1 (-2200 2350)(-1875 2350);
WIRE 16 -1 (-1875 2525)(-1875 2350);
WIRE 16 -1 (-1550 2350)(-1550 2525);
WIRE 16 -1 (2875 4200)(3725 4200);
FORCEPROP 2 LAST SIG_NAME P2E_GPU_TX_DN
J 0
(3015 4210);
DISPLAY 0.851064 (3015 4210);
WIRE 16 -1 (3725 4550)(2875 4550);
FORCEPROP 2 LAST SIG_NAME P2E_PCH_TX_DN
J 0
(3040 4560);
DISPLAY 0.808511 (3040 4560);
WIRE 16 -1 (3725 4600)(2875 4600);
FORCEPROP 2 LAST SIG_NAME P2E_PCH_TX_DP
J 0
(3040 4610);
DISPLAY 0.808511 (3040 4610);
WIRE 16 -1 (2175 -1100)(3475 -1100);
FORCEPROP 2 LAST SIG_NAME SMB_BMC_MM10_SDA
J 2
(3390 -1090);
DISPLAY 0.808511 (3390 -1090);
WIRE 16 -1 (2175 -950)(3475 -950);
FORCEPROP 2 LAST SIG_NAME SMB_BMC_MM9_SCL
J 2
(3350 -940);
DISPLAY 0.808511 (3350 -940);
WIRE 16 -1 (2175 -1000)(3475 -1000);
FORCEPROP 2 LAST SIG_NAME SMB_BMC_MM9_SDA
J 2
(3350 -990);
DISPLAY 0.808511 (3350 -990);
WIRE 16 -1 (2175 -1050)(3475 -1050);
FORCEPROP 2 LAST SIG_NAME SMB_BMC_MM10_SCL
J 2
(3390 -1040);
DISPLAY 0.808511 (3390 -1040);
WIRE 16 -1 (4700 -950)(5875 -950);
FORCEPROP 2 LAST SIG_NAME FM_THERMTRIP_DLY_LVC1_R_N
J 0
(4865 -940);
DISPLAY 0.851064 (4865 -940);
WIRE 16 -1 (5825 -350)(4875 -350);
FORCEPROP 2 LAST SIG_NAME SMB_BMC_MM5_SCL
J 2
(5790 -340);
DISPLAY 0.808511 (5790 -340);
WIRE 16 -1 (3925 4600)(4750 4600);
FORCEPROP 2 LAST SIG_NAME P2E_PCH_TX_C_DP
J 0
(4165 4610);
DISPLAY 0.808511 (4165 4610);
WIRE 16 -1 (3925 4550)(4750 4550);
FORCEPROP 2 LAST SIG_NAME P2E_PCH_TX_C_DN
J 0
(4165 4560);
DISPLAY 0.808511 (4165 4560);
WIRE 16 -1 (775 3000)(-25 3000);
WIRE 16 -1 (775 3050)(-25 3050);
WIRE 16 -1 (775 3100)(-25 3100);
WIRE 16 -1 (775 3150)(-25 3150);
WIRE 16 -1 (775 3200)(-25 3200);
WIRE 16 -1 (775 3250)(-25 3250);
WIRE 16 -1 (775 3300)(-25 3300);
WIRE 16 -1 (775 2950)(-25 2950);
WIRE 16 -1 (775 3350)(-25 3350);
WIRE 16 -1 (775 3600)(-25 3600);
WIRE 16 -1 (-375 3900)(775 3900);
FORCEPROP 2 LAST SIG_NAME NC_DP_BMC_AUX_P
J 0
(-285 3910);
DISPLAY 0.808511 (-285 3910);
WIRE 16 -1 (775 3850)(-375 3850);
FORCEPROP 2 LAST SIG_NAME NC_DP_BMC_AUX_N
J 0
(-285 3860);
DISPLAY 0.808511 (-285 3860);
WIRE 16 -1 (625 3700)(775 3700);
WIRE 16 -1 (625 3800)(625 3700);
WIRE 16 -1 (-475 3800)(625 3800);
FORCEPROP 2 LAST SIG_NAME DP_BMC_HPD_3V3_BUF
J 2
(390 3810);
DISPLAY 0.808511 (390 3810);
WIRE 16 -1 (-2275 2100)(-950 2100);
FORCEPROP 2 LAST SIG_NAME ESPI_HOST_LPC_BMC_CLK
J 0
(-2185 2110);
DISPLAY 0.808511 (-2185 2110);
WIRE 16 -1 (775 2900)(-25 2900);
WIRE 16 -1 (775 2850)(-25 2850);
WIRE 16 -1 (-300 2750)(775 2750);
FORCEPROP 2 LAST SIG_NAME M_BMC_DDR4_DQS0_P
J 0
(-260 2760);
DISPLAY 0.808511 (-260 2760);
WIRE 16 -1 (-300 2700)(775 2700);
FORCEPROP 2 LAST SIG_NAME M_BMC_DDR4_DQS1_P
J 0
(-260 2710);
DISPLAY 0.808511 (-260 2710);
WIRE 16 -1 (-300 2650)(775 2650);
FORCEPROP 2 LAST SIG_NAME M_BMC_DDR4_DQS0_N
J 0
(-260 2660);
DISPLAY 0.808511 (-260 2660);
WIRE 16 -1 (-2275 2050)(-950 2050);
FORCEPROP 2 LAST SIG_NAME ESPI_HOST_LPC_BMC_LFRAME_N
J 0
(-2185 2060);
DISPLAY 0.808511 (-2185 2060);
WIRE 16 -1 (775 200)(-550 200);
FORCEPROP 2 LAST SIG_NAME SMB_BMC_MM16_R_SCL
J 2
(525 210);
DISPLAY 0.808511 (525 210);
WIRE 16 -1 (775 750)(-750 750);
FORCEPROP 2 LAST SIG_NAME FM_BMC_DBP_PRESENT_R_N
J 0
(-360 760);
DISPLAY 0.808511 (-360 760);
WIRE 16 -1 (-550 500)(775 500);
FORCEPROP 2 LAST SIG_NAME SGPIO_BMC_M1_CLK
J 2
(440 510);
DISPLAY 0.808511 (440 510);
WIRE 16 -1 (-550 450)(775 450);
FORCEPROP 2 LAST SIG_NAME SGPIO_BMC_M1_LD
J 2
(415 460);
DISPLAY 0.808511 (415 460);
WIRE 16 -1 (-550 400)(775 400);
FORCEPROP 2 LAST SIG_NAME SGPIO_BMC_M1_DO
J 2
(415 410);
DISPLAY 0.808511 (415 410);
WIRE 16 -1 (-550 350)(775 350);
FORCEPROP 2 LAST SIG_NAME SGPIO_BMC_M1_DI
J 2
(415 360);
DISPLAY 0.808511 (415 360);
WIRE 16 -1 (775 300)(-550 300);
FORCEPROP 2 LAST SIG_NAME SMB_BMC_MM15_R_SCL
J 2
(525 310);
DISPLAY 0.808511 (525 310);
WIRE 16 -1 (775 250)(-550 250);
FORCEPROP 2 LAST SIG_NAME SMB_BMC_MM15_R_SDA
J 2
(525 260);
DISPLAY 0.808511 (525 260);
WIRE 16 -1 (-1725 -1150)(-875 -1150);
FORCEPROP 2 LAST SIG_NAME RST_PLTRST_N
J 0
(-1660 -1140);
DISPLAY 0.808511 (-1660 -1140);
WIRE 16 -1 (1975 -1050)(1025 -1050);
FORCEPROP 2 LAST SIG_NAME SMB_BMC_MM10_R_SCL
J 0
(1065 -1040);
DISPLAY 0.808511 (1065 -1040);
WIRE 16 -1 (1975 -1000)(1025 -1000);
FORCEPROP 2 LAST SIG_NAME SMB_BMC_MM9_R_SDA
J 0
(1065 -990);
DISPLAY 0.808511 (1065 -990);
WIRE 16 -1 (1975 -950)(1025 -950);
FORCEPROP 2 LAST SIG_NAME SMB_BMC_MM9_R_SCL
J 0
(1065 -940);
DISPLAY 0.808511 (1065 -940);
WIRE 16 2175 (2425 -475)(2775 -475);
WIRE 16 2175 (2425 -200)(2425 -475);
WIRE 16 2175 (2775 -475)(2775 -200);
WIRE 16 2175 (2775 -200)(2425 -200);
WIRE 16 -1 (5825 -500)(4875 -500);
FORCEPROP 2 LAST SIG_NAME SMB_BMC_MM7_SDA
J 2
(5790 -490);
DISPLAY 0.808511 (5790 -490);
WIRE 16 -1 (3625 -350)(4675 -350);
FORCEPROP 2 LAST SIG_NAME SMB_BMC_MM5_R_SCL
J 2
(4290 -340);
DISPLAY 0.808511 (4290 -340);
WIRE 16 -1 (3625 -450)(4675 -450);
FORCEPROP 2 LAST SIG_NAME SMB_BMC_MM7_R_SCL
J 2
(4290 -440);
DISPLAY 0.808511 (4290 -440);
WIRE 16 -1 (3625 -400)(4675 -400);
FORCEPROP 2 LAST SIG_NAME SMB_BMC_MM5_R_SDA
J 2
(4290 -390);
DISPLAY 0.808511 (4290 -390);
WIRE 16 -1 (4025 550)(2875 550);
FORCEPROP 2 LAST SIG_NAME SMB_BMC_MM12_R_SCL
J 0
(3100 560);
DISPLAY 0.808511 (3100 560);
WIRE 16 -1 (3725 2200)(2875 2200);
FORCEPROP 2 LAST SIG_NAME M_BMC_DDR4_MDM1
J 0
(2965 2210);
DISPLAY 0.808511 (2965 2210);
WIRE 16 -1 (3725 2250)(2875 2250);
FORCEPROP 2 LAST SIG_NAME M_BMC_DDR4_MDM0
J 0
(2965 2260);
DISPLAY 0.808511 (2965 2260);
WIRE 16 -1 (3725 2300)(2875 2300);
FORCEPROP 0 LAST SIG_NAME M_BMC_DDR4_MBG1
J 0
(2965 2310);
DISPLAY 0.808511 (2965 2310);
WIRE 16 -1 (3725 2350)(2875 2350);
FORCEPROP 2 LAST SIG_NAME M_BMC_DDR4_MACT_N
J 0
(2965 2360);
DISPLAY 0.808511 (2965 2360);
WIRE 16 -1 (2875 2500)(4125 2500);
WIRE 16 -1 (3650 3150)(2875 3150);
FORCEPROP 2 LAST SIG_NAME M_BMC_DDR4_MBA1
J 0
(2965 3160);
DISPLAY 0.808511 (2965 3160);
WIRE 16 -1 (2875 4150)(3725 4150);
FORCEPROP 2 LAST SIG_NAME P2E_GPU_TX_DP
J 0
(3015 4160);
DISPLAY 0.851064 (3015 4160);
WIRE 16 -1 (-375 4500)(775 4500);
FORCEPROP 2 LAST SIG_NAME CLK_100M_PCH_DP
J 0
(-285 4510);
DISPLAY 0.808511 (-285 4510);
WIRE 16 -1 (-1300 3300)(-2450 3300);
FORCEPROP 2 LAST SIG_NAME FM_PCH_BMC_THERMTRIP_N
J 2
(-1335 3310);
DISPLAY 0.808511 (-1335 3310);
WIRE 16 -1 (-1300 3225)(-2450 3225);
FORCEPROP 2 LAST SIG_NAME FM_BMC_DBP_PRESENT_N
J 2
(-1335 3235);
DISPLAY 0.808511 (-1335 3235);
WIRE 16 -1 (-2275 1950)(-950 1950);
FORCEPROP 2 LAST SIG_NAME RST_BMC_LPC_ESPI_N
J 0
(-2185 1960);
DISPLAY 0.808511 (-2185 1960);
WIRE 16 -1 (-2075 1050)(-950 1050);
FORCEPROP 2 LAST SIG_NAME UART_6_BMC_RXD
J 2
(-1500 1060);
DISPLAY 0.808511 (-1500 1060);
WIRE 16 -1 (3925 4150)(4750 4150);
FORCEPROP 2 LAST SIG_NAME P2E_GPU_TX_C_DP
J 0
(4165 4160);
DISPLAY 0.851064 (4165 4160);
WIRE 16 -1 (3925 4200)(4750 4200);
FORCEPROP 2 LAST SIG_NAME P2E_GPU_TX_C_DN
J 0
(4165 4210);
DISPLAY 0.851064 (4165 4210);
WIRE 16 3135 (3950 4025)(3950 4850);
WIRE 16 3135 (3600 4025)(3950 4025);
WIRE 16 3135 (3950 4850)(3600 4850);
WIRE 16 3135 (3600 4850)(3600 4025);
WIRE 16 -1 (-2275 2000)(-950 2000);
FORCEPROP 2 LAST SIG_NAME IRQ_BMC_LPC_SERIRQ_ESPI_GF
J 0
(-2185 2010);
DISPLAY 0.808511 (-2185 2010);
WIRE 16 3135 (-2425 1350)(-2425 1825);
WIRE 16 3135 (-2425 1350)(-1450 1350);
WIRE 16 3135 (-1450 1825)(-2425 1825);
WIRE 16 3135 (-1450 1825)(-1450 1350);
WIRE 16 -1 (-2075 500)(-750 500);
FORCEPROP 2 LAST SIG_NAME SGPIO_CLK_1
J 0
(-2050 510);
DISPLAY 0.808511 (-2050 510);
WIRE 16 -1 (-750 400)(-2075 400);
FORCEPROP 2 LAST SIG_NAME SGPIO_DO_1
J 0
(-2050 410);
DISPLAY 0.808511 (-2050 410);
WIRE 16 -1 (-1375 -325)(-250 -325);
FORCEPROP 2 LAST SIG_NAME ESPI_HOST_LPC_BMC_LFRAME_N
J 0
(-1225 -315);
DISPLAY 0.808511 (-1225 -315);
WIRE 16 -1 (-250 -375)(-1375 -375);
FORCEPROP 2 LAST SIG_NAME IRQ_BMC_LPC_SERIRQ_ESPI_GF
J 0
(-1225 -365);
DISPLAY 0.808511 (-1225 -365);
WIRE 16 3135 (-1600 -350)(-1350 -350);
WIRE 16 3135 (-1600 -225)(-1600 -350);
WIRE 16 3135 (-1350 -350)(-1350 -225);
WIRE 16 3135 (-1350 -225)(-1600 -225);
WIRE 16 -1 (-2425 25)(-1500 25);
FORCEPROP 2 LAST SIG_NAME SMB_BMC_MM16_R5_SDA
J 0
(-2400 35);
DISPLAY 0.808511 (-2400 35);
WIRE 16 -1 (-1300 75)(-1175 75);
WIRE 16 -1 (-1175 75)(-1175 200);
WIRE 16 -1 (-1175 200)(-750 200);
WIRE 16 -1 (-2075 200)(-1175 200);
FORCEPROP 2 LAST SIG_NAME SMB_BMC_MM16_SCL
J 0
(-2050 210);
DISPLAY 0.808511 (-2050 210);
WIRE 16 -1 (775 150)(-550 150);
FORCEPROP 2 LAST SIG_NAME SMB_BMC_MM16_R_SDA
J 2
(525 160);
DISPLAY 0.808511 (525 160);
WIRE 16 -1 (-675 -1150)(75 -1150);
FORCEPROP 2 LAST SIG_NAME RST_PLTRST_R_N
J 0
(-510 -1140);
DISPLAY 0.808511 (-510 -1140);
WIRE 16 3135 (600 -1000)(-2475 -1000);
WIRE 16 3135 (600 -1000)(600 -1275);
WIRE 16 3135 (-2475 -1275)(-2475 -1000);
WIRE 16 3135 (-2475 -1275)(600 -1275);
WIRE 16 -1 (1975 -1100)(1025 -1100);
FORCEPROP 2 LAST SIG_NAME SMB_BMC_MM10_R_SDA
J 0
(1065 -1090);
DISPLAY 0.808511 (1065 -1090);
WIRE 16 3135 (-1525 50)(-1275 50);
WIRE 16 3135 (-1525 125)(-1525 50);
WIRE 16 3135 (-1275 50)(-1275 125);
WIRE 16 3135 (-1275 125)(-1525 125);
WIRE 16 -1 (-2425 75)(-1500 75);
FORCEPROP 2 LAST SIG_NAME SMB_BMC_MM16_R5_SCL
J 0
(-2400 85);
DISPLAY 0.808511 (-2400 85);
WIRE 16 -1 (-300 2600)(775 2600);
FORCEPROP 2 LAST SIG_NAME M_BMC_DDR4_DQS1_N
J 0
(-260 2610);
DISPLAY 0.808511 (-260 2610);
WIRE 16 -1 (-300 2500)(775 2500);
FORCEPROP 2 LAST SIG_NAME M_BMC_DDR4_RST_N
J 0
(-260 2510);
DISPLAY 0.808511 (-260 2510);
WIRE 16 -1 (3650 3200)(2875 3200);
FORCEPROP 2 LAST SIG_NAME M_BMC_DDR4_MBA0
J 0
(2965 3210);
DISPLAY 0.808511 (2965 3210);
WIRE 16 -1 (3650 3250)(2875 3250);
FORCEPROP 2 LAST SIG_NAME M_BMC_DDR4_MWE_N
J 0
(2965 3260);
DISPLAY 0.808511 (2965 3260);
WIRE 16 -1 (3650 3300)(2875 3300);
FORCEPROP 2 LAST SIG_NAME M_BMC_DDR4_MCAS_N
J 0
(2965 3310);
DISPLAY 0.808511 (2965 3310);
WIRE 16 -1 (3650 3500)(2875 3500);
FORCEPROP 2 LAST SIG_NAME M_BMC_DDR4_MCKE
J 0
(2965 3510);
DISPLAY 0.808511 (2965 3510);
WIRE 16 -1 (775 3550)(-25 3550);
WIRE 16 -1 (775 3500)(-25 3500);
WIRE 16 -1 (775 3450)(-25 3450);
WIRE 16 -1 (775 3400)(-25 3400);
WIRE 16 -1 (3650 3350)(2875 3350);
FORCEPROP 2 LAST SIG_NAME M_BMC_DDR4_MRAS_N
J 0
(2965 3360);
DISPLAY 0.808511 (2965 3360);
WIRE 16 -1 (3650 3600)(2875 3600);
FORCEPROP 2 LAST SIG_NAME M_BMC_DDR4_MCLK_DP
J 0
(2965 3610);
DISPLAY 0.808511 (2965 3610);
WIRE 16 -1 (2875 2900)(4125 2900);
WIRE 16 -1 (2875 2800)(4125 2800);
WIRE 16 -1 (2875 2750)(4125 2750);
WIRE 16 -1 (2875 2700)(4125 2700);
WIRE 16 -1 (2875 2650)(4125 2650);
WIRE 16 -1 (2875 2600)(4125 2600);
WIRE 16 -1 (2875 2550)(4125 2550);
WIRE 16 -1 (3650 3100)(2875 3100);
FORCEPROP 2 LAST SIG_NAME M_BMC_DDR4_MBG0
J 0
(2965 3110);
DISPLAY 0.808511 (2965 3110);
WIRE 16 -1 (3650 3550)(2875 3550);
FORCEPROP 2 LAST SIG_NAME M_BMC_DDR4_MCLK_DN
J 0
(2965 3560);
DISPLAY 0.808511 (2965 3560);
WIRE 16 -1 (3700 3700)(2875 3700);
FORCEPROP 2 LAST SIG_NAME NC_DP_BMC_TX1_N
J 0
(3115 3710);
DISPLAY 0.808511 (3115 3710);
WIRE 16 -1 (3700 3750)(2875 3750);
FORCEPROP 2 LAST SIG_NAME NC_DP_BMC_TX1_P
J 0
(3115 3760);
DISPLAY 0.808511 (3115 3760);
WIRE 16 -1 (3700 3850)(2875 3850);
FORCEPROP 2 LAST SIG_NAME NC_DP_BMC_TX0_N
J 0
(3115 3860);
DISPLAY 0.808511 (3115 3860);
WIRE 16 -1 (3700 3900)(2875 3900);
FORCEPROP 2 LAST SIG_NAME NC_DP_BMC_TX0_P
J 0
(3115 3910);
DISPLAY 0.808511 (3115 3910);
WIRE 16 -1 (775 4000)(-375 4000);
FORCEPROP 2 LAST SIG_NAME P2E_GPU_RX_DN
J 0
(-285 4010);
DISPLAY 0.808511 (-285 4010);
PAINT WHITE (-285 4010);
WIRE 16 -1 (775 4050)(-375 4050);
FORCEPROP 2 LAST SIG_NAME P2E_GPU_RX_DP
J 0
(-285 4060);
DISPLAY 0.808511 (-285 4060);
PAINT WHITE (-285 4060);
WIRE 16 -1 (775 4150)(-375 4150);
FORCEPROP 2 LAST SIG_NAME CLK_100M_GPU_DN
J 0
(-285 4160);
DISPLAY 0.808511 (-285 4160);
PAINT WHITE (-285 4160);
WIRE 16 -1 (775 4200)(-375 4200);
FORCEPROP 2 LAST SIG_NAME CLK_100M_GPU_DP
J 0
(-285 4210);
DISPLAY 0.808511 (-285 4210);
PAINT WHITE (-285 4210);
WIRE 16 -1 (-375 4300)(775 4300);
FORCEPROP 2 LAST SIG_NAME P2E_PCH_RX_DN
J 0
(-285 4310);
DISPLAY 0.808511 (-285 4310);
WIRE 16 -1 (-375 4350)(775 4350);
FORCEPROP 2 LAST SIG_NAME P2E_PCH_RX_DP
J 0
(-285 4360);
DISPLAY 0.808511 (-285 4360);
WIRE 16 -1 (-375 4450)(775 4450);
FORCEPROP 2 LAST SIG_NAME CLK_100M_PCH_DN
J 0
(-285 4460);
DISPLAY 0.808511 (-285 4460);
WIRE 16 -1 (-1050 4600)(-1125 4600);
WIRE 16 -1 (-1050 4600)(-1050 4800);
WIRE 16 -1 (775 4600)(-1050 4600);
FORCEPROP 2 LAST SIG_NAME RST_PLTRST_N
J 0
(-960 4610);
DISPLAY 0.808511 (-960 4610);
WIRE 16 -1 (2875 2450)(4125 2450);
WIRE 16 -1 (2875 2400)(4125 2400);
WIRE 16 -1 (-300 2450)(775 2450);
FORCEPROP 2 LAST SIG_NAME M_BMC_DDR4_ALERT_N
J 0
(-260 2460);
DISPLAY 0.808511 (-260 2460);
WIRE 16 -1 (775 2200)(-100 2200);
FORCEPROP 2 LAST SIG_NAME IBMC_MIOZ
J 0
(115 2210);
DISPLAY 0.808511 (115 2210);
WIRE 16 -1 (3725 2100)(2875 2100);
FORCEPROP 2 LAST SIG_NAME ESPI_LPC_D0_IO0
J 0
(2990 2110);
DISPLAY 0.808511 (2990 2110);
WIRE 16 -1 (3725 2050)(2875 2050);
FORCEPROP 2 LAST SIG_NAME ESPI_LPC_D1_IO1
J 0
(2990 2060);
DISPLAY 0.808511 (2990 2060);
WIRE 16 -1 (3725 1950)(2875 1950);
FORCEPROP 2 LAST SIG_NAME ESPI_LPC_D3_IO3
J 0
(2990 1960);
DISPLAY 0.808511 (2990 1960);
WIRE 16 -1 (3725 2000)(2875 2000);
FORCEPROP 2 LAST SIG_NAME ESPI_LPC_D2_IO2
J 0
(2990 2010);
DISPLAY 0.808511 (2990 2010);
DOT 1 (-1875 -325);
DOT 1 (150 2350);
DOT 1 (-1875 -375);
DOT 1 (-1275 -425);
DOT 1 (-2200 2875);
DOT 1 (3100 100);
DOT 1 (3050 200);
DOT 1 (3025 250);
DOT 1 (2250 -300);
DOT 1 (-1875 2875);
DOT 1 (-1700 2350);
DOT 1 (-2775 3300);
DOT 1 (-1550 2875);
DOT 1 (2250 -400);
DOT 1 (2250 -350);
DOT 1 (3075 150);
DOT 1 (-1875 2350);
DOT 1 (-1175 200);
DOT 1 (-1050 4600);
DOT 1 (-1125 150);
FORCENOTE
CHANGE TO 40HM_20221206
(3825 1425) 0;
DISPLAY LEFT (3825 1425);
DISPLAY 0.638298 (3825 1425);
PAINT WHITE (3825 1425);
FORCENOTE
CHANGE EMMC IO PORT TO SD1,SD2
(-2750 1275) 0;
DISPLAY LEFT (-2750 1275);
DISPLAY 1.021277 (-2750 1275);
PAINT WHITE (-2750 1275);
FORCENOTE
CHANGE TO 200OHM_20220804
(-975 75) 0;
DISPLAY LEFT (-975 75);
DISPLAY 0.808511 (-975 75);
PAINT WHITE (-975 75);
FORCENOTE
DEPOP_20220426
(-1675 -200) 0;
DISPLAY LEFT (-1675 -200);
DISPLAY 0.808511 (-1675 -200);
PAINT WHITE (-1675 -200);
FORCENOTE
PLACE CLOSE TO U5
(3400 4950) 0;
DISPLAY LEFT (3400 4950);
DISPLAY 1.595745 (3400 4950);
PAINT WHITE (3400 4950);
QUIT
